FILE_TYPE = MACRO_DRAWING;
SET COLOR_WIRE YELLOW;
SET COLOR_PROP ORANGE;
SET COLOR_DOT WHITE;
SET COLOR_ARC YELLOW;
SET COLOR_BODY GREEN;
SET COLOR_NOTE PURPLE;
SET PROP_DISPLAY VALUE;
SET PAGE_NUMBER P260;
FORCEADD OFFPAGE..1
(-10875 2475);
FORCEPROP 2 LAST $XR2 276 
J 0
(-11367 2475);
DISPLAY 0.638298 (-11367 2475);
PAINT MONO (-11367 2475);
FORCEPROP 2 LAST $XR1 275 
J 0
(-11247 2475);
DISPLAY 0.638298 (-11247 2475);
PAINT MONO (-11247 2475);
FORCEPROP 2 LAST $XR0 274 
J 0
(-11127 2475);
DISPLAY 0.638298 (-11127 2475);
PAINT MONO (-11127 2475);
FORCEPROP 1 LAST COMMENT_BODY TRUE
J 0
(-10750 2375);
DISPLAY 0.872340 (-10750 2375);
PAINT GREEN (-10750 2375);
DISPLAY INVISIBLE (-10750 2375);
FORCEPROP 1 LAST OFFPAGE TRUE
J 0
(-10550 2350);
DISPLAY 0.872340 (-10550 2350);
PAINT GREEN (-10550 2350);
DISPLAY INVISIBLE (-10550 2350);
FORCEPROP 2 LAST CDS_LIB standard
J 0
(-10875 2475);
DISPLAY INVISIBLE (-10875 2475);
FORCEPROP 2 LAST PATH I1
J 0
(-11125 2525);
DISPLAY 1.021277 (-11125 2525);
DISPLAY INVISIBLE (-11125 2525);
FORCEADD Q_RES..1
(-9275 2225);
FORCEPROP 1 LAST PART_NUMBER CS00002JB13
J 0
(-9150 2175);
DISPLAY 0.617021 (-9150 2175);
PAINT BLUE (-9150 2175);
DISPLAY INVISIBLE (-9150 2175);
FORCEPROP 1 LAST VALUE 0
J 2
(-9125 2225);
DISPLAY 0.617021 (-9125 2225);
PAINT SKYBLUE (-9125 2225);
FORCEPROP 1 LAST TOLERANCE 5%
J 0
(-9100 2225);
DISPLAY 0.617021 (-9100 2225);
PAINT SKYBLUE (-9100 2225);
FORCEPROP 1 LAST PACK_TYPE 0402LF
J 0
(-9025 2225);
DISPLAY 0.617021 (-9025 2225);
PAINT SKYBLUE (-9025 2225);
FORCEPROP 1 LAST MATERIAL EMPTY
J 0
(-8775 2225);
DISPLAY 0.617021 (-8775 2225);
PAINT RED (-8775 2225);
FORCEPROP 1 LAST LOCATION PR107
J 0
(-9500 2225);
DISPLAY 0.617021 (-9500 2225);
PAINT AQUA (-9500 2225);
FORCEPROP 1 LASTPIN (-9375 2225) $PN 1
J 0
(-9363 2237);
DISPLAY 0.617021 (-9363 2237);
PAINT MONO (-9363 2237);
FORCEPROP 1 LASTPIN (-9175 2225) $PN 2
J 0
(-9213 2237);
DISPLAY 0.617021 (-9213 2237);
PAINT MONO (-9213 2237);
FORCEPROP 2 LAST CDS_LIB pure_quanta
J 0
(-9275 2225);
DISPLAY INVISIBLE (-9275 2225);
FORCEPROP 1 LAST WATTAGE 1/16W
J 2
(-8900 2125);
DISPLAY 0.510638 (-8900 2125);
PAINT SKYBLUE (-8900 2125);
DISPLAY INVISIBLE (-8900 2125);
FORCEPROP 1 LAST PATH I10
J 0
(-9325 2375);
DISPLAY 0.978723 (-9325 2375);
PAINT WHITE (-9325 2375);
DISPLAY INVISIBLE (-9325 2375);
FORCEPROP 1 LAST LOCATION PR107
J 0
(-9325 2325);
DISPLAY 1.021277 (-9325 2325);
PAINT AQUA (-9325 2325);
DISPLAY INVISIBLE (-9325 2325);
FORCEPROP 0 LAST $SEC 1
J 0
(-9325 2325);
DISPLAY 0.680851 (-9325 2325);
PAINT MONO (-9325 2325);
DISPLAY INVISIBLE (-9325 2325);
FORCEPROP 0 LAST CDS_SEC 1
J 0
(-9325 2325);
DISPLAY 1.021277 (-9325 2325);
DISPLAY INVISIBLE (-9325 2325);
FORCEADD Q_RES..1
(-4850 7575);
FORCEPROP 1 LAST PART_NUMBER CS-1002FB04
J 0
(-4700 7525);
DISPLAY 0.617021 (-4700 7525);
PAINT BLUE (-4700 7525);
DISPLAY INVISIBLE (-4700 7525);
FORCEPROP 1 LAST MATERIAL CHIP
J 0
(-4550 7575);
DISPLAY 0.617021 (-4550 7575);
PAINT SKYBLUE (-4550 7575);
FORCEPROP 1 LAST WATTAGE 1/16W
J 2
(-4400 7475);
DISPLAY 0.617021 (-4400 7475);
PAINT SKYBLUE (-4400 7475);
FORCEPROP 1 LAST TOLERANCE 1%
J 0
(-4650 7575);
DISPLAY 0.617021 (-4650 7575);
PAINT SKYBLUE (-4650 7575);
FORCEPROP 1 LAST VALUE 1
J 2
(-4675 7575);
DISPLAY 0.617021 (-4675 7575);
PAINT SKYBLUE (-4675 7575);
FORCEPROP 1 LAST PACK_TYPE 0402LF
J 0
(-4700 7475);
DISPLAY 0.617021 (-4700 7475);
PAINT SKYBLUE (-4700 7475);
FORCEPROP 1 LAST LOCATION PR130
J 0
(-5075 7575);
DISPLAY 0.617021 (-5075 7575);
PAINT AQUA (-5075 7575);
FORCEPROP 1 LASTPIN (-4950 7575) $PN 1
J 0
(-4938 7587);
DISPLAY 0.617021 (-4938 7587);
PAINT MONO (-4938 7587);
FORCEPROP 1 LASTPIN (-4750 7575) $PN 2
J 0
(-4788 7587);
DISPLAY 0.617021 (-4788 7587);
PAINT MONO (-4788 7587);
FORCEPROP 2 LAST CDS_LIB pure_quanta
J 0
(-4850 7575);
DISPLAY INVISIBLE (-4850 7575);
FORCEPROP 1 LAST PATH I100
J 0
(-4900 7725);
DISPLAY 0.978723 (-4900 7725);
PAINT WHITE (-4900 7725);
DISPLAY INVISIBLE (-4900 7725);
FORCEPROP 1 LAST LOCATION PR130
J 0
(-4900 7675);
DISPLAY 1.021277 (-4900 7675);
PAINT AQUA (-4900 7675);
DISPLAY INVISIBLE (-4900 7675);
FORCEPROP 0 LAST $SEC 1
J 0
(-4900 7675);
DISPLAY 0.680851 (-4900 7675);
PAINT MONO (-4900 7675);
DISPLAY INVISIBLE (-4900 7675);
FORCEPROP 0 LAST CDS_SEC 1
J 0
(-4900 7675);
DISPLAY 1.021277 (-4900 7675);
DISPLAY INVISIBLE (-4900 7675);
FORCEADD UNIVERSAL_GND..1
R 3
(-4725 6700);
FORCEPROP 3 LASTPIN (-4775 6700) SIG_NAME GND\g
J 0
(-4765 6710);
DISPLAY 0.659574 (-4765 6710);
PAINT MONO (-4765 6710);
DISPLAY INVISIBLE (-4765 6710);
FORCEPROP 1 LAST HDL_POWER GND
R 1
J 1
(-4650 6675);
DISPLAY 0.872340 (-4650 6675);
PAINT GREEN (-4650 6675);
DISPLAY INVISIBLE (-4650 6675);
FORCEPROP 2 LAST CDS_LIB logical_power
J 0
(-4725 6700);
PAINT MONO (-4725 6700);
DISPLAY INVISIBLE (-4725 6700);
FORCEPROP 1 LAST PATH I101
R 1
J 2
(-4725 6625);
DISPLAY 0.872340 (-4725 6625);
PAINT AQUA (-4725 6625);
DISPLAY INVISIBLE (-4725 6625);
FORCEADD OFFPAGE..2
(-4725 7100);
FORCEPROP 2 LAST $XR2 276 
J 0
(-4296 7100);
DISPLAY 0.638298 (-4296 7100);
PAINT MONO (-4296 7100);
FORCEPROP 2 LAST $XR1 275 
J 0
(-4416 7100);
DISPLAY 0.638298 (-4416 7100);
PAINT MONO (-4416 7100);
FORCEPROP 2 LAST $XR0 274 
J 0
(-4536 7100);
DISPLAY 0.638298 (-4536 7100);
PAINT MONO (-4536 7100);
FORCEPROP 1 LAST COMMENT_BODY TRUE
J 0
(-4770 7005);
DISPLAY 0.872340 (-4770 7005);
PAINT GREEN (-4770 7005);
DISPLAY INVISIBLE (-4770 7005);
FORCEPROP 1 LAST OFFPAGE TRUE
J 0
(-4400 6975);
DISPLAY 0.872340 (-4400 6975);
PAINT GREEN (-4400 6975);
DISPLAY INVISIBLE (-4400 6975);
FORCEPROP 2 LAST CDS_LIB standard
J 0
(-4725 7100);
PAINT MONO (-4725 7100);
DISPLAY INVISIBLE (-4725 7100);
FORCEPROP 2 LAST PATH I102
J 0
(-4275 7150);
DISPLAY 1.021277 (-4275 7150);
DISPLAY INVISIBLE (-4275 7150);
FORCEADD UNIVERSAL_GND..1
R 3
(-4725 7175);
FORCEPROP 3 LASTPIN (-4775 7175) SIG_NAME GND\g
J 0
(-4765 7185);
DISPLAY 0.659574 (-4765 7185);
PAINT MONO (-4765 7185);
DISPLAY INVISIBLE (-4765 7185);
FORCEPROP 1 LAST HDL_POWER GND
R 1
J 1
(-4650 7150);
DISPLAY 0.872340 (-4650 7150);
PAINT GREEN (-4650 7150);
DISPLAY INVISIBLE (-4650 7150);
FORCEPROP 2 LAST CDS_LIB logical_power
J 0
(-4725 7175);
PAINT MONO (-4725 7175);
DISPLAY INVISIBLE (-4725 7175);
FORCEPROP 1 LAST PATH I103
R 1
J 2
(-4725 7100);
DISPLAY 0.872340 (-4725 7100);
PAINT AQUA (-4725 7100);
DISPLAY INVISIBLE (-4725 7100);
FORCEADD VCC15..1
(-4375 7700);
FORCEPROP 3 LASTPIN (-4375 7650) SIG_NAME P3V3_AUX\g
J 0
(-4365 7660);
DISPLAY 0.659574 (-4365 7660);
PAINT MONO (-4365 7660);
DISPLAY INVISIBLE (-4365 7660);
FORCEPROP 1 LAST HDL_POWER P3V3_AUX
J 1
(-4375 7750);
DISPLAY 0.617021 (-4375 7750);
PAINT GREEN (-4375 7750);
FORCEPROP 2 LAST CDS_LIB logical_power
J 0
(-4375 7700);
DISPLAY INVISIBLE (-4375 7700);
FORCEPROP 1 LAST PATH I104
J 0
(-4325 7725);
DISPLAY 0.872340 (-4325 7725);
PAINT AQUA (-4325 7725);
DISPLAY INVISIBLE (-4325 7725);
FORCEADD UNIVERSAL_GND..1
(-3750 2225);
FORCEPROP 3 LASTPIN (-3750 2275) SIG_NAME GND\g
J 0
(-3740 2285);
DISPLAY 0.659574 (-3740 2285);
PAINT MONO (-3740 2285);
DISPLAY INVISIBLE (-3740 2285);
FORCEPROP 1 LAST HDL_POWER GND
J 1
(-3725 2150);
DISPLAY 0.872340 (-3725 2150);
PAINT GREEN (-3725 2150);
DISPLAY INVISIBLE (-3725 2150);
FORCEPROP 2 LAST CDS_LIB logical_power
J 0
(-3750 2225);
DISPLAY INVISIBLE (-3750 2225);
FORCEPROP 1 LAST PATH I105
J 0
(-3675 2225);
DISPLAY 0.872340 (-3675 2225);
PAINT AQUA (-3675 2225);
DISPLAY INVISIBLE (-3675 2225);
FORCEADD Q_RES..2
(-3750 2475);
FORCEPROP 1 LAST PART_NUMBER CS31002FB08
J 0
(-3710 2350);
DISPLAY 0.617021 (-3710 2350);
PAINT BLUE (-3710 2350);
DISPLAY INVISIBLE (-3710 2350);
FORCEPROP 1 LAST PACK_TYPE 0402LF
J 0
(-3710 2300);
DISPLAY 0.617021 (-3710 2300);
PAINT SKYBLUE (-3710 2300);
FORCEPROP 1 LAST WATTAGE 1/16W
J 0
(-3710 2450);
DISPLAY 0.617021 (-3710 2450);
PAINT SKYBLUE (-3710 2450);
FORCEPROP 1 LAST MATERIAL EMPTY
J 0
(-3710 2400);
DISPLAY 0.617021 (-3710 2400);
PAINT RED (-3710 2400);
FORCEPROP 1 LAST TOLERANCE 1%
J 0
(-3705 2500);
DISPLAY 0.617021 (-3705 2500);
PAINT SKYBLUE (-3705 2500);
FORCEPROP 1 LAST VALUE 10K
J 0
(-3705 2550);
DISPLAY 0.617021 (-3705 2550);
PAINT SKYBLUE (-3705 2550);
FORCEPROP 1 LAST LOCATION PR436
J 0
(-3705 2600);
DISPLAY 0.617021 (-3705 2600);
PAINT AQUA (-3705 2600);
FORCEPROP 2 LAST CDS_LIB pure_quanta
J 0
(-3750 2475);
DISPLAY INVISIBLE (-3750 2475);
FORCEPROP 1 LAST PATH I106
J 0
(-3700 2650);
DISPLAY 0.978723 (-3700 2650);
PAINT WHITE (-3700 2650);
DISPLAY INVISIBLE (-3700 2650);
FORCEPROP 0 LAST $SEC 1
J 0
(-3700 2650);
DISPLAY INVISIBLE (-3700 2650);
FORCEPROP 0 LAST CDS_SEC 1
J 0
(-3700 2650);
DISPLAY INVISIBLE (-3700 2650);
FORCEPROP 1 LASTPIN (-3750 2575) $PN 1
J 0
(-3745 2537);
DISPLAY 0.787234 (-3745 2537);
PAINT MONO (-3745 2537);
DISPLAY INVISIBLE (-3745 2537);
FORCEPROP 1 LASTPIN (-3750 2375) $PN 2
J 0
(-3745 2385);
DISPLAY 0.787234 (-3745 2385);
PAINT MONO (-3745 2385);
DISPLAY INVISIBLE (-3745 2385);
FORCEADD OFFPAGE..4
(-3325 2675);
FORCEPROP 2 LAST $XR0 276 
J 0
(-3139 2675);
DISPLAY 0.638298 (-3139 2675);
PAINT MONO (-3139 2675);
FORCEPROP 1 LAST COMMENT_BODY TRUE
J 0
(-3350 2575);
DISPLAY 0.872340 (-3350 2575);
PAINT GREEN (-3350 2575);
DISPLAY INVISIBLE (-3350 2575);
FORCEPROP 1 LAST OFFPAGE TRUE
J 0
(-3000 2550);
DISPLAY 0.872340 (-3000 2550);
PAINT GREEN (-3000 2550);
DISPLAY INVISIBLE (-3000 2550);
FORCEPROP 2 LAST CDS_LIB standard
J 0
(-3325 2675);
DISPLAY INVISIBLE (-3325 2675);
FORCEPROP 2 LAST PATH I107
J 0
(-3125 2725);
DISPLAY 1.021277 (-3125 2725);
DISPLAY INVISIBLE (-3125 2725);
FORCEADD OFFPAGE..2
(-3325 3075);
FORCEPROP 2 LAST $XR0 214 
J 0
(-3136 3075);
DISPLAY 0.638298 (-3136 3075);
PAINT MONO (-3136 3075);
FORCEPROP 1 LAST COMMENT_BODY TRUE
J 0
(-3370 2980);
DISPLAY 0.872340 (-3370 2980);
PAINT GREEN (-3370 2980);
DISPLAY INVISIBLE (-3370 2980);
FORCEPROP 1 LAST OFFPAGE TRUE
J 0
(-3000 2950);
DISPLAY 0.872340 (-3000 2950);
PAINT GREEN (-3000 2950);
DISPLAY INVISIBLE (-3000 2950);
FORCEPROP 2 LAST CDS_LIB standard
J 0
(-3325 3075);
DISPLAY INVISIBLE (-3325 3075);
FORCEPROP 2 LAST PATH I108
J 0
(-3000 3125);
DISPLAY 1.021277 (-3000 3125);
DISPLAY INVISIBLE (-3000 3125);
FORCEADD Q_RES..2
(-9750 2250);
FORCEPROP 1 LAST PART_NUMBER CS16812FB02
J 2
(-9825 2125);
DISPLAY 0.638298 (-9825 2125);
DISPLAY INVISIBLE (-9825 2125);
FORCEPROP 1 LAST TOLERANCE 1%
J 2
(-9825 2275);
DISPLAY 0.638298 (-9825 2275);
FORCEPROP 1 LAST VALUE 681
J 2
(-9825 2325);
DISPLAY 0.638298 (-9825 2325);
FORCEPROP 1 LAST PACK_TYPE 0402LF
J 2
(-9825 2075);
DISPLAY 0.638298 (-9825 2075);
FORCEPROP 1 LAST MATERIAL CHIP
J 2
(-9825 2175);
DISPLAY 0.638298 (-9825 2175);
FORCEPROP 1 LAST WATTAGE 1/16W
J 2
(-9825 2225);
DISPLAY 0.638298 (-9825 2225);
FORCEPROP 1 LAST LOCATION PR106
J 2
(-9825 2375);
DISPLAY 0.638298 (-9825 2375);
FORCEPROP 1 LASTPIN (-9750 2350) $PN 1
J 0
(-9745 2312);
DISPLAY 0.787234 (-9745 2312);
PAINT MONO (-9745 2312);
FORCEPROP 1 LASTPIN (-9750 2150) $PN 2
J 0
(-9745 2160);
DISPLAY 0.787234 (-9745 2160);
PAINT MONO (-9745 2160);
FORCEPROP 1 LAST PATH I109
J 0
(-9700 2425);
DISPLAY 0.978723 (-9700 2425);
PAINT WHITE (-9700 2425);
DISPLAY INVISIBLE (-9700 2425);
FORCEPROP 2 LAST CDS_LIB pure_quanta
J 0
(-9750 2250);
DISPLAY INVISIBLE (-9750 2250);
FORCEPROP 0 LAST $SEC 1
J 0
(-9825 2425);
DISPLAY 0.680851 (-9825 2425);
PAINT MONO (-9825 2425);
DISPLAY INVISIBLE (-9825 2425);
FORCEPROP 0 LAST CDS_SEC 1
J 0
(-9825 2425);
DISPLAY 1.021277 (-9825 2425);
DISPLAY INVISIBLE (-9825 2425);
FORCEADD Q_RES..1
(-9025 2775);
FORCEPROP 1 LAST PART_NUMBER CS00002JB13
J 0
(-8900 2825);
DISPLAY 0.617021 (-8900 2825);
PAINT BLUE (-8900 2825);
DISPLAY INVISIBLE (-8900 2825);
FORCEPROP 1 LAST WATTAGE 1/16W
J 2
(-8600 2875);
DISPLAY 0.617021 (-8600 2875);
PAINT SKYBLUE (-8600 2875);
FORCEPROP 1 LAST TOLERANCE 5%
J 0
(-8850 2775);
DISPLAY 0.617021 (-8850 2775);
PAINT SKYBLUE (-8850 2775);
FORCEPROP 1 LAST VALUE 0
J 2
(-8875 2775);
DISPLAY 0.617021 (-8875 2775);
PAINT SKYBLUE (-8875 2775);
FORCEPROP 1 LAST MATERIAL CHIP
J 0
(-8900 2875);
DISPLAY 0.617021 (-8900 2875);
PAINT SKYBLUE (-8900 2875);
FORCEPROP 1 LAST PACK_TYPE 0402LF
J 0
(-8775 2775);
DISPLAY 0.617021 (-8775 2775);
PAINT SKYBLUE (-8775 2775);
FORCEPROP 1 LAST LOCATION R2397
J 0
(-9250 2775);
DISPLAY 0.617021 (-9250 2775);
PAINT AQUA (-9250 2775);
FORCEPROP 1 LASTPIN (-9125 2775) $PN 1
J 0
(-9113 2787);
DISPLAY 0.617021 (-9113 2787);
PAINT MONO (-9113 2787);
FORCEPROP 1 LASTPIN (-8925 2775) $PN 2
J 0
(-8963 2787);
DISPLAY 0.617021 (-8963 2787);
PAINT MONO (-8963 2787);
FORCEPROP 2 LAST CDS_LIB pure_quanta
J 0
(-9025 2775);
DISPLAY INVISIBLE (-9025 2775);
FORCEPROP 1 LAST PATH I11
J 0
(-9075 2925);
DISPLAY 0.978723 (-9075 2925);
PAINT WHITE (-9075 2925);
DISPLAY INVISIBLE (-9075 2925);
FORCEPROP 1 LAST LOCATION R2397
J 0
(-9075 2875);
DISPLAY 1.021277 (-9075 2875);
PAINT AQUA (-9075 2875);
DISPLAY INVISIBLE (-9075 2875);
FORCEPROP 0 LAST $SEC 1
J 0
(-9075 2875);
DISPLAY 0.680851 (-9075 2875);
PAINT MONO (-9075 2875);
DISPLAY INVISIBLE (-9075 2875);
FORCEPROP 0 LAST CDS_SEC 1
J 0
(-9075 2875);
DISPLAY 1.021277 (-9075 2875);
DISPLAY INVISIBLE (-9075 2875);
FORCEADD Q_CAP..1
(-5925 7375);
FORCEPROP 1 LAST PART_NUMBER CH4104K1B00
J 0
(-5875 7300);
DISPLAY 0.638298 (-5875 7300);
DISPLAY INVISIBLE (-5875 7300);
FORCEPROP 1 LAST PACK_TYPE 0402
J 0
(-5875 7250);
DISPLAY 0.638298 (-5875 7250);
FORCEPROP 1 LAST VALUE 0.1UF
J 0
(-5875 7450);
DISPLAY 0.638298 (-5875 7450);
FORCEPROP 1 LAST VOLTAGE 25V
J 0
(-5875 7400);
DISPLAY 0.638298 (-5875 7400);
FORCEPROP 1 LAST TOLERANCE 10%
J 0
(-5875 7350);
DISPLAY 0.638298 (-5875 7350);
FORCEPROP 1 LAST MATERIAL EMPTY
J 0
(-5875 7325);
DISPLAY 0.638298 (-5875 7325);
PAINT RED (-5875 7325);
FORCEPROP 1 LAST LOCATION PC2362
J 0
(-5875 7475);
DISPLAY 0.978723 (-5875 7475);
FORCEPROP 1 LASTPIN (-5925 7475) $PN 1
J 0
(-5915 7455);
DISPLAY 0.787234 (-5915 7455);
PAINT MONO (-5915 7455);
FORCEPROP 1 LASTPIN (-5925 7275) $PN 2
J 0
(-5915 7255);
DISPLAY 0.787234 (-5915 7255);
PAINT MONO (-5915 7255);
FORCEPROP 1 LAST PATH I110
J 0
(-5875 7525);
DISPLAY 0.978723 (-5875 7525);
PAINT WHITE (-5875 7525);
DISPLAY INVISIBLE (-5875 7525);
FORCEPROP 2 LAST CDS_LIB pure_quanta
J 0
(-5925 7375);
DISPLAY INVISIBLE (-5925 7375);
FORCEPROP 0 LAST $SEC 1
J 0
(-5875 7525);
DISPLAY 0.680851 (-5875 7525);
PAINT MONO (-5875 7525);
DISPLAY INVISIBLE (-5875 7525);
FORCEPROP 0 LAST CDS_SEC 1
J 0
(-5875 7525);
DISPLAY 1.021277 (-5875 7525);
DISPLAY INVISIBLE (-5875 7525);
FORCEADD VCC15..1
(-9500 3025);
FORCEPROP 3 LASTPIN (-9500 2975) SIG_NAME P3V3_AUX\g
J 0
(-9490 2985);
DISPLAY 0.659574 (-9490 2985);
PAINT MONO (-9490 2985);
DISPLAY INVISIBLE (-9490 2985);
FORCEPROP 1 LAST HDL_POWER P3V3_AUX
J 1
(-9500 3075);
DISPLAY 0.617021 (-9500 3075);
PAINT GREEN (-9500 3075);
FORCEPROP 2 LAST CDS_LIB logical_power
J 0
(-9500 3025);
PAINT MONO (-9500 3025);
DISPLAY INVISIBLE (-9500 3025);
FORCEPROP 1 LAST PATH I12
J 0
(-9450 3050);
DISPLAY 0.872340 (-9450 3050);
PAINT AQUA (-9450 3050);
DISPLAY INVISIBLE (-9450 3050);
FORCEADD Q_RES..1
(-9025 2925);
FORCEPROP 1 LAST PART_NUMBER CS21002FB06
J 0
(-8900 2975);
DISPLAY 0.617021 (-8900 2975);
PAINT BLUE (-8900 2975);
DISPLAY INVISIBLE (-8900 2975);
FORCEPROP 1 LAST TOLERANCE 1%
J 0
(-8825 2925);
DISPLAY 0.617021 (-8825 2925);
PAINT SKYBLUE (-8825 2925);
FORCEPROP 1 LAST PACK_TYPE 0402LF
J 0
(-8725 2925);
DISPLAY 0.617021 (-8725 2925);
PAINT SKYBLUE (-8725 2925);
FORCEPROP 1 LAST WATTAGE 1/16W
J 2
(-8600 3025);
DISPLAY 0.617021 (-8600 3025);
PAINT SKYBLUE (-8600 3025);
FORCEPROP 1 LAST MATERIAL CHIP
J 0
(-8900 3025);
DISPLAY 0.617021 (-8900 3025);
PAINT SKYBLUE (-8900 3025);
FORCEPROP 1 LAST VALUE 1K
J 2
(-8850 2925);
DISPLAY 0.617021 (-8850 2925);
PAINT SKYBLUE (-8850 2925);
FORCEPROP 1 LAST LOCATION R2396
J 0
(-9250 2925);
DISPLAY 0.617021 (-9250 2925);
PAINT AQUA (-9250 2925);
FORCEPROP 1 LASTPIN (-9125 2925) $PN 1
J 0
(-9113 2937);
DISPLAY 0.617021 (-9113 2937);
PAINT MONO (-9113 2937);
FORCEPROP 1 LASTPIN (-8925 2925) $PN 2
J 0
(-8963 2937);
DISPLAY 0.617021 (-8963 2937);
PAINT MONO (-8963 2937);
FORCEPROP 2 LAST CDS_LIB pure_quanta
J 0
(-9025 2925);
DISPLAY INVISIBLE (-9025 2925);
FORCEPROP 1 LAST PATH I13
J 0
(-9075 3075);
DISPLAY 0.978723 (-9075 3075);
PAINT WHITE (-9075 3075);
DISPLAY INVISIBLE (-9075 3075);
FORCEPROP 1 LAST LOCATION R2396
J 0
(-9075 3025);
DISPLAY 1.021277 (-9075 3025);
PAINT AQUA (-9075 3025);
DISPLAY INVISIBLE (-9075 3025);
FORCEPROP 0 LAST $SEC 1
J 0
(-9075 3025);
DISPLAY 0.680851 (-9075 3025);
PAINT MONO (-9075 3025);
DISPLAY INVISIBLE (-9075 3025);
FORCEPROP 0 LAST CDS_SEC 1
J 0
(-9075 3025);
DISPLAY 1.021277 (-9075 3025);
DISPLAY INVISIBLE (-9075 3025);
FORCEADD Q_RES..1
(-9025 3175);
FORCEPROP 1 LAST PART_NUMBER CS00002JB13
J 0
(-8900 3225);
DISPLAY 0.617021 (-8900 3225);
PAINT BLUE (-8900 3225);
DISPLAY INVISIBLE (-8900 3225);
FORCEPROP 1 LAST TOLERANCE 5%
J 0
(-8850 3175);
DISPLAY 0.617021 (-8850 3175);
PAINT SKYBLUE (-8850 3175);
FORCEPROP 1 LAST VALUE 0
J 2
(-8875 3175);
DISPLAY 0.617021 (-8875 3175);
PAINT SKYBLUE (-8875 3175);
FORCEPROP 1 LAST PACK_TYPE 0402LF
J 0
(-8775 3175);
DISPLAY 0.617021 (-8775 3175);
PAINT SKYBLUE (-8775 3175);
FORCEPROP 1 LAST WATTAGE 1/16W
J 2
(-8600 3275);
DISPLAY 0.617021 (-8600 3275);
PAINT SKYBLUE (-8600 3275);
FORCEPROP 1 LAST MATERIAL CHIP
J 0
(-8900 3275);
DISPLAY 0.617021 (-8900 3275);
PAINT SKYBLUE (-8900 3275);
FORCEPROP 1 LAST LOCATION R2394
J 0
(-9250 3175);
DISPLAY 0.617021 (-9250 3175);
PAINT AQUA (-9250 3175);
FORCEPROP 1 LASTPIN (-9125 3175) $PN 1
J 0
(-9113 3187);
DISPLAY 0.617021 (-9113 3187);
PAINT MONO (-9113 3187);
FORCEPROP 1 LASTPIN (-8925 3175) $PN 2
J 0
(-8963 3187);
DISPLAY 0.617021 (-8963 3187);
PAINT MONO (-8963 3187);
FORCEPROP 2 LAST CDS_LIB pure_quanta
J 0
(-9025 3175);
DISPLAY INVISIBLE (-9025 3175);
FORCEPROP 1 LAST PATH I14
J 0
(-9075 3325);
DISPLAY 0.978723 (-9075 3325);
PAINT WHITE (-9075 3325);
DISPLAY INVISIBLE (-9075 3325);
FORCEPROP 1 LAST LOCATION R2394
J 0
(-9075 3275);
DISPLAY 1.021277 (-9075 3275);
PAINT AQUA (-9075 3275);
DISPLAY INVISIBLE (-9075 3275);
FORCEPROP 0 LAST $SEC 1
J 0
(-9075 3275);
DISPLAY 0.680851 (-9075 3275);
PAINT MONO (-9075 3275);
DISPLAY INVISIBLE (-9075 3275);
FORCEPROP 0 LAST CDS_SEC 1
J 0
(-9075 3275);
DISPLAY 1.021277 (-9075 3275);
DISPLAY INVISIBLE (-9075 3275);
FORCEADD UNIVERSAL_GND..1
(-9350 3850);
FORCEPROP 3 LASTPIN (-9350 3900) SIG_NAME GND\g
J 0
(-9340 3910);
DISPLAY 0.659574 (-9340 3910);
PAINT MONO (-9340 3910);
DISPLAY INVISIBLE (-9340 3910);
FORCEPROP 1 LAST HDL_POWER GND
J 1
(-9325 3775);
DISPLAY 0.872340 (-9325 3775);
PAINT GREEN (-9325 3775);
DISPLAY INVISIBLE (-9325 3775);
FORCEPROP 2 LAST CDS_LIB logical_power
J 0
(-9350 3850);
PAINT MONO (-9350 3850);
DISPLAY INVISIBLE (-9350 3850);
FORCEPROP 1 LAST PATH I15
J 0
(-9275 3850);
DISPLAY 0.872340 (-9275 3850);
PAINT AQUA (-9275 3850);
DISPLAY INVISIBLE (-9275 3850);
FORCEADD VCC15..1
(-9350 3700);
FORCEPROP 3 LASTPIN (-9350 3650) SIG_NAME P3V3_AUX\g
J 0
(-9340 3660);
DISPLAY 0.659574 (-9340 3660);
PAINT MONO (-9340 3660);
DISPLAY INVISIBLE (-9340 3660);
FORCEPROP 1 LAST HDL_POWER P3V3_AUX
J 1
(-9350 3750);
DISPLAY 0.617021 (-9350 3750);
PAINT GREEN (-9350 3750);
FORCEPROP 2 LAST CDS_LIB logical_power
J 0
(-9350 3700);
DISPLAY INVISIBLE (-9350 3700);
FORCEPROP 1 LAST PATH I16
J 0
(-9300 3725);
DISPLAY 0.872340 (-9300 3725);
PAINT AQUA (-9300 3725);
DISPLAY INVISIBLE (-9300 3725);
FORCEADD Q_RES..1
(-9025 3475);
FORCEPROP 1 LAST PART_NUMBER CS21002FB06
J 0
(-8900 3525);
DISPLAY 0.510638 (-8900 3525);
PAINT BLUE (-8900 3525);
DISPLAY INVISIBLE (-8900 3525);
FORCEPROP 1 LAST VALUE 1K
J 2
(-8850 3475);
DISPLAY 0.617021 (-8850 3475);
PAINT SKYBLUE (-8850 3475);
FORCEPROP 1 LAST TOLERANCE 1%
J 0
(-8825 3475);
DISPLAY 0.617021 (-8825 3475);
PAINT SKYBLUE (-8825 3475);
FORCEPROP 1 LAST PACK_TYPE 0402LF
J 0
(-8750 3475);
DISPLAY 0.617021 (-8750 3475);
PAINT SKYBLUE (-8750 3475);
FORCEPROP 1 LAST LOCATION R2393
J 0
(-9275 3475);
DISPLAY 0.617021 (-9275 3475);
PAINT AQUA (-9275 3475);
FORCEPROP 1 LASTPIN (-9125 3475) $PN 1
J 0
(-9113 3487);
DISPLAY 0.617021 (-9113 3487);
FORCEPROP 1 LASTPIN (-8925 3475) $PN 2
J 0
(-8963 3487);
DISPLAY 0.617021 (-8963 3487);
FORCEPROP 2 LAST CDS_LIB pure_quanta
J 0
(-9025 3475);
PAINT MONO (-9025 3475);
DISPLAY INVISIBLE (-9025 3475);
FORCEPROP 1 LAST WATTAGE 1/16W
J 2
(-8650 3575);
DISPLAY 0.510638 (-8650 3575);
PAINT SKYBLUE (-8650 3575);
DISPLAY INVISIBLE (-8650 3575);
FORCEPROP 1 LAST MATERIAL CHIP
J 0
(-8900 3575);
DISPLAY 0.510638 (-8900 3575);
PAINT SKYBLUE (-8900 3575);
DISPLAY INVISIBLE (-8900 3575);
FORCEPROP 1 LAST PATH I17
J 0
(-9075 3625);
DISPLAY 0.978723 (-9075 3625);
PAINT WHITE (-9075 3625);
DISPLAY INVISIBLE (-9075 3625);
FORCEPROP 2 LAST $SEC 1
J 0
(-9075 3675);
DISPLAY 0.680851 (-9075 3675);
PAINT MONO (-9075 3675);
DISPLAY INVISIBLE (-9075 3675);
FORCEPROP 2 LAST CDS_SEC 1
J 0
(-9075 3675);
DISPLAY 1.021277 (-9075 3675);
DISPLAY INVISIBLE (-9075 3675);
FORCEADD Q_RES..1
(-9025 3575);
FORCEPROP 1 LAST PART_NUMBER CS21002FB06
J 0
(-8900 3625);
DISPLAY 0.617021 (-8900 3625);
PAINT BLUE (-8900 3625);
DISPLAY INVISIBLE (-8900 3625);
FORCEPROP 1 LAST MATERIAL CHIP
J 0
(-8900 3675);
DISPLAY 0.617021 (-8900 3675);
PAINT SKYBLUE (-8900 3675);
FORCEPROP 1 LAST TOLERANCE 1%
J 0
(-8825 3575);
DISPLAY 0.617021 (-8825 3575);
PAINT SKYBLUE (-8825 3575);
FORCEPROP 1 LAST WATTAGE 1/16W
J 2
(-8600 3675);
DISPLAY 0.617021 (-8600 3675);
PAINT SKYBLUE (-8600 3675);
FORCEPROP 1 LAST PACK_TYPE 0402LF
J 0
(-8750 3575);
DISPLAY 0.617021 (-8750 3575);
PAINT SKYBLUE (-8750 3575);
FORCEPROP 1 LAST VALUE 1K
J 2
(-8850 3575);
DISPLAY 0.617021 (-8850 3575);
PAINT SKYBLUE (-8850 3575);
FORCEPROP 1 LAST LOCATION R2392
J 0
(-9275 3575);
DISPLAY 0.617021 (-9275 3575);
PAINT AQUA (-9275 3575);
FORCEPROP 1 LASTPIN (-9125 3575) $PN 1
J 0
(-9113 3587);
DISPLAY 0.617021 (-9113 3587);
FORCEPROP 1 LASTPIN (-8925 3575) $PN 2
J 0
(-8963 3587);
DISPLAY 0.617021 (-8963 3587);
FORCEPROP 2 LAST CDS_LIB pure_quanta
J 0
(-9025 3575);
PAINT MONO (-9025 3575);
DISPLAY INVISIBLE (-9025 3575);
FORCEPROP 1 LAST PATH I18
J 0
(-9075 3725);
DISPLAY 0.978723 (-9075 3725);
PAINT WHITE (-9075 3725);
DISPLAY INVISIBLE (-9075 3725);
FORCEPROP 2 LAST $SEC 1
J 0
(-9075 3775);
DISPLAY 0.680851 (-9075 3775);
PAINT MONO (-9075 3775);
DISPLAY INVISIBLE (-9075 3775);
FORCEPROP 2 LAST CDS_SEC 1
J 0
(-9075 3775);
DISPLAY 1.021277 (-9075 3775);
DISPLAY INVISIBLE (-9075 3775);
FORCEADD Q_RES..2
(-8825 1925);
FORCEPROP 1 LAST PART_NUMBER CS00002JB13
J 0
(-8785 1800);
DISPLAY 0.510638 (-8785 1800);
DISPLAY INVISIBLE (-8785 1800);
FORCEPROP 1 LAST MATERIAL CHIP
J 0
(-8785 1850);
DISPLAY 0.510638 (-8785 1850);
PAINT RED (-8785 1850);
FORCEPROP 1 LAST WATTAGE 1/16W
J 0
(-8785 1900);
DISPLAY 0.510638 (-8785 1900);
FORCEPROP 1 LAST VALUE 0
J 0
(-8780 2000);
DISPLAY 0.510638 (-8780 2000);
FORCEPROP 1 LAST PACK_TYPE 0402LF
J 0
(-8785 1750);
DISPLAY 0.510638 (-8785 1750);
FORCEPROP 1 LAST TOLERANCE 5%
J 0
(-8780 1950);
DISPLAY 0.510638 (-8780 1950);
FORCEPROP 1 LAST LOCATION PR4220
J 0
(-8780 2050);
DISPLAY 0.978723 (-8780 2050);
FORCEPROP 1 LASTPIN (-8825 2025) $PN 1
J 0
(-8820 1987);
DISPLAY 0.787234 (-8820 1987);
PAINT MONO (-8820 1987);
FORCEPROP 1 LASTPIN (-8825 1825) $PN 2
J 0
(-8820 1835);
DISPLAY 0.787234 (-8820 1835);
PAINT MONO (-8820 1835);
FORCEPROP 2 LAST CDS_LIB pure_quanta
J 0
(-8825 1925);
DISPLAY INVISIBLE (-8825 1925);
FORCEPROP 1 LAST PATH I19
J 0
(-8775 2100);
DISPLAY 0.978723 (-8775 2100);
PAINT WHITE (-8775 2100);
DISPLAY INVISIBLE (-8775 2100);
FORCEPROP 0 LAST $SEC 1
J 0
(-8775 2100);
DISPLAY 0.680851 (-8775 2100);
PAINT MONO (-8775 2100);
DISPLAY INVISIBLE (-8775 2100);
FORCEPROP 0 LAST CDS_SEC 1
J 0
(-8775 2100);
DISPLAY 1.021277 (-8775 2100);
DISPLAY INVISIBLE (-8775 2100);
FORCEADD OFFPAGE..5
(-10150 2775);
FORCEPROP 2 LAST $XR1 253 
J 0
(-10555 2775);
DISPLAY 0.638298 (-10555 2775);
PAINT MONO (-10555 2775);
FORCEPROP 2 LAST $XR0 214 
J 0
(-10435 2775);
DISPLAY 0.638298 (-10435 2775);
PAINT MONO (-10435 2775);
FORCEPROP 1 LAST COMMENT_BODY TRUE
J 0
(-10050 2700);
DISPLAY 0.872340 (-10050 2700);
PAINT GREEN (-10050 2700);
DISPLAY INVISIBLE (-10050 2700);
FORCEPROP 1 LAST OFFPAGE TRUE
J 0
(-9825 2650);
DISPLAY 0.872340 (-9825 2650);
PAINT GREEN (-9825 2650);
DISPLAY INVISIBLE (-9825 2650);
FORCEPROP 2 LAST CDS_LIB standard
J 0
(-10150 2775);
DISPLAY INVISIBLE (-10150 2775);
FORCEPROP 2 LAST PATH I2
J 0
(-10425 2825);
DISPLAY 1.021277 (-10425 2825);
DISPLAY INVISIBLE (-10425 2825);
FORCEADD Q_CAP..1
(-8500 1925);
FORCEPROP 1 LAST PART_NUMBER CH4104K1B00
J 0
(-8450 1750);
DISPLAY 0.617021 (-8450 1750);
PAINT BLUE (-8450 1750);
DISPLAY INVISIBLE (-8450 1750);
FORCEPROP 1 LAST MATERIAL EMPTY
J 0
(-8450 1850);
DISPLAY 0.617021 (-8450 1850);
PAINT RED (-8450 1850);
FORCEPROP 1 LAST PACK_TYPE 0402
J 0
(-8450 1800);
DISPLAY 0.617021 (-8450 1800);
PAINT SKYBLUE (-8450 1800);
FORCEPROP 1 LAST TOLERANCE 10%
J 0
(-8450 1900);
DISPLAY 0.617021 (-8450 1900);
PAINT SKYBLUE (-8450 1900);
FORCEPROP 1 LAST VOLTAGE 25V
J 0
(-8450 1950);
DISPLAY 0.617021 (-8450 1950);
PAINT SKYBLUE (-8450 1950);
FORCEPROP 1 LAST VALUE 0.1UF
J 0
(-8450 2000);
DISPLAY 0.617021 (-8450 2000);
PAINT SKYBLUE (-8450 2000);
FORCEPROP 1 LAST LOCATION PC214
J 0
(-8450 2050);
DISPLAY 0.617021 (-8450 2050);
PAINT AQUA (-8450 2050);
FORCEPROP 1 LASTPIN (-8500 2025) $PN 1
J 0
(-8490 2005);
DISPLAY 0.617021 (-8490 2005);
PAINT MONO (-8490 2005);
FORCEPROP 1 LASTPIN (-8500 1825) $PN 2
J 0
(-8490 1805);
DISPLAY 0.617021 (-8490 1805);
PAINT MONO (-8490 1805);
FORCEPROP 2 LAST CDS_LIB pure_quanta
J 0
(-8500 1925);
DISPLAY INVISIBLE (-8500 1925);
FORCEPROP 1 LAST PATH I20
J 0
(-8450 2075);
DISPLAY 0.978723 (-8450 2075);
PAINT WHITE (-8450 2075);
DISPLAY INVISIBLE (-8450 2075);
FORCEPROP 1 LAST LOCATION PC214
J 0
(-8450 2100);
DISPLAY 1.021277 (-8450 2100);
PAINT AQUA (-8450 2100);
DISPLAY INVISIBLE (-8450 2100);
FORCEPROP 0 LAST $SEC 1
J 0
(-8450 2100);
DISPLAY 0.680851 (-8450 2100);
PAINT MONO (-8450 2100);
DISPLAY INVISIBLE (-8450 2100);
FORCEPROP 0 LAST CDS_SEC 1
J 0
(-8450 2100);
DISPLAY 1.021277 (-8450 2100);
DISPLAY INVISIBLE (-8450 2100);
FORCEADD Q_RES..2
(-8075 1925);
FORCEPROP 1 LAST PART_NUMBER CS21002FB06
J 0
(-8035 1800);
DISPLAY 0.617021 (-8035 1800);
PAINT BLUE (-8035 1800);
DISPLAY INVISIBLE (-8035 1800);
FORCEPROP 1 LAST VALUE 1K
J 0
(-8030 2000);
DISPLAY 0.617021 (-8030 2000);
PAINT SKYBLUE (-8030 2000);
FORCEPROP 1 LAST WATTAGE 1/16W
J 0
(-8035 1900);
DISPLAY 0.617021 (-8035 1900);
PAINT SKYBLUE (-8035 1900);
FORCEPROP 1 LAST MATERIAL EMPTY
J 0
(-8035 1850);
DISPLAY 0.617021 (-8035 1850);
PAINT RED (-8035 1850);
FORCEPROP 1 LAST TOLERANCE 1%
J 0
(-8030 1950);
DISPLAY 0.617021 (-8030 1950);
PAINT SKYBLUE (-8030 1950);
FORCEPROP 1 LAST PACK_TYPE 0402LF
J 0
(-8035 1750);
DISPLAY 0.617021 (-8035 1750);
PAINT SKYBLUE (-8035 1750);
FORCEPROP 1 LAST LOCATION PR123
J 0
(-8030 2050);
DISPLAY 0.617021 (-8030 2050);
PAINT AQUA (-8030 2050);
FORCEPROP 1 LASTPIN (-8075 2025) $PN 1
J 0
(-8070 1987);
DISPLAY 0.617021 (-8070 1987);
PAINT MONO (-8070 1987);
FORCEPROP 1 LASTPIN (-8075 1825) $PN 2
J 0
(-8070 1835);
DISPLAY 0.617021 (-8070 1835);
PAINT MONO (-8070 1835);
FORCEPROP 2 LAST CDS_LIB pure_quanta
J 0
(-8075 1925);
DISPLAY INVISIBLE (-8075 1925);
FORCEPROP 1 LAST PATH I21
J 0
(-8025 2100);
DISPLAY 0.978723 (-8025 2100);
PAINT WHITE (-8025 2100);
DISPLAY INVISIBLE (-8025 2100);
FORCEPROP 1 LAST LOCATION PR123
J 0
(-8025 2100);
DISPLAY 1.021277 (-8025 2100);
PAINT AQUA (-8025 2100);
DISPLAY INVISIBLE (-8025 2100);
FORCEPROP 0 LAST $SEC 1
J 0
(-8025 2100);
DISPLAY 0.680851 (-8025 2100);
PAINT MONO (-8025 2100);
DISPLAY INVISIBLE (-8025 2100);
FORCEPROP 0 LAST CDS_SEC 1
J 0
(-8025 2100);
DISPLAY 1.021277 (-8025 2100);
DISPLAY INVISIBLE (-8025 2100);
FORCEADD Q_CAP..2
(-8225 2925);
FORCEPROP 1 LAST PART_NUMBER TMP_QCH21006JB10
J 1
(-7950 2875);
DISPLAY 0.617021 (-7950 2875);
PAINT BLUE (-7950 2875);
DISPLAY INVISIBLE (-7950 2875);
FORCEPROP 1 LAST TOLERANCE 5%
J 2
(-7575 2875);
DISPLAY 0.617021 (-7575 2875);
PAINT SKYBLUE (-7575 2875);
FORCEPROP 1 LAST MATERIAL EMPTY
J 0
(-7750 2925);
DISPLAY 0.617021 (-7750 2925);
PAINT RED (-7750 2925);
FORCEPROP 1 LAST VOLTAGE 50V
J 0
(-7875 2925);
DISPLAY 0.617021 (-7875 2925);
PAINT SKYBLUE (-7875 2925);
FORCEPROP 1 LAST VALUE 1000PF
J 2
(-7900 2925);
DISPLAY 0.617021 (-7900 2925);
PAINT SKYBLUE (-7900 2925);
FORCEPROP 1 LAST PACK_TYPE 0402
J 1
(-7675 2850);
DISPLAY 0.617021 (-7675 2850);
PAINT SKYBLUE (-7675 2850);
FORCEPROP 1 LAST LOCATION C3276
J 1
(-8425 2925);
DISPLAY 0.617021 (-8425 2925);
PAINT AQUA (-8425 2925);
FORCEPROP 1 LASTPIN (-8325 2925) $PN 1
J 0
(-8335 2940);
DISPLAY 0.617021 (-8335 2940);
PAINT MONO (-8335 2940);
FORCEPROP 1 LASTPIN (-8125 2925) $PN 2
J 0
(-8140 2940);
DISPLAY 0.617021 (-8140 2940);
PAINT MONO (-8140 2940);
FORCEPROP 2 LAST CDS_LIB pure_quanta
J 0
(-8225 2925);
DISPLAY INVISIBLE (-8225 2925);
FORCEPROP 1 LAST PATH I22
J 0
(-8225 3125);
DISPLAY 0.978723 (-8225 3125);
PAINT WHITE (-8225 3125);
DISPLAY INVISIBLE (-8225 3125);
FORCEPROP 1 LAST LOCATION C3276
J 0
(-8275 3025);
DISPLAY 1.021277 (-8275 3025);
PAINT AQUA (-8275 3025);
DISPLAY INVISIBLE (-8275 3025);
FORCEPROP 0 LAST $SEC 1
J 0
(-8275 3025);
DISPLAY 0.680851 (-8275 3025);
PAINT MONO (-8275 3025);
DISPLAY INVISIBLE (-8275 3025);
FORCEPROP 0 LAST CDS_SEC 1
J 0
(-8275 3025);
DISPLAY 1.021277 (-8275 3025);
DISPLAY INVISIBLE (-8275 3025);
FORCEADD Q_CAP..2
(-8225 3050);
FORCEPROP 1 LAST PART_NUMBER TMP_QCH21006JB10
J 1
(-7950 3000);
DISPLAY 0.617021 (-7950 3000);
PAINT BLUE (-7950 3000);
DISPLAY INVISIBLE (-7950 3000);
FORCEPROP 1 LAST VOLTAGE 50V
J 0
(-7875 3050);
DISPLAY 0.617021 (-7875 3050);
PAINT SKYBLUE (-7875 3050);
FORCEPROP 1 LAST MATERIAL X7R
J 0
(-7750 3050);
DISPLAY 0.617021 (-7750 3050);
PAINT SKYBLUE (-7750 3050);
FORCEPROP 1 LAST PACK_TYPE 0402
J 1
(-7675 2975);
DISPLAY 0.617021 (-7675 2975);
PAINT SKYBLUE (-7675 2975);
FORCEPROP 1 LAST TOLERANCE 5%
J 2
(-7575 3000);
DISPLAY 0.617021 (-7575 3000);
PAINT SKYBLUE (-7575 3000);
FORCEPROP 1 LAST VALUE 1000PF
J 2
(-7900 3050);
DISPLAY 0.617021 (-7900 3050);
PAINT SKYBLUE (-7900 3050);
FORCEPROP 1 LAST LOCATION C3275
J 1
(-8425 3050);
DISPLAY 0.617021 (-8425 3050);
PAINT AQUA (-8425 3050);
FORCEPROP 1 LASTPIN (-8325 3050) $PN 1
J 0
(-8335 3065);
DISPLAY 0.617021 (-8335 3065);
PAINT MONO (-8335 3065);
FORCEPROP 1 LASTPIN (-8125 3050) $PN 2
J 0
(-8140 3065);
DISPLAY 0.617021 (-8140 3065);
PAINT MONO (-8140 3065);
FORCEPROP 2 LAST CDS_LIB pure_quanta
J 0
(-8225 3050);
DISPLAY INVISIBLE (-8225 3050);
FORCEPROP 1 LAST PATH I23
J 0
(-8225 3250);
DISPLAY 0.978723 (-8225 3250);
PAINT WHITE (-8225 3250);
DISPLAY INVISIBLE (-8225 3250);
FORCEPROP 1 LAST LOCATION C3275
J 0
(-8275 3150);
DISPLAY 1.021277 (-8275 3150);
PAINT AQUA (-8275 3150);
DISPLAY INVISIBLE (-8275 3150);
FORCEPROP 0 LAST $SEC 1
J 0
(-8275 3150);
DISPLAY 0.680851 (-8275 3150);
PAINT MONO (-8275 3150);
DISPLAY INVISIBLE (-8275 3150);
FORCEPROP 0 LAST CDS_SEC 1
J 0
(-8275 3150);
DISPLAY 1.021277 (-8275 3150);
DISPLAY INVISIBLE (-8275 3150);
FORCEADD OFFPAGE..1
(-11100 4100);
FORCEPROP 2 LAST $XR0 16 
J 0
(-11381 4100);
DISPLAY 0.638298 (-11381 4100);
PAINT MONO (-11381 4100);
FORCEPROP 1 LAST COMMENT_BODY TRUE
J 0
(-10975 4000);
DISPLAY 0.872340 (-10975 4000);
PAINT GREEN (-10975 4000);
DISPLAY INVISIBLE (-10975 4000);
FORCEPROP 1 LAST OFFPAGE TRUE
J 0
(-10775 3975);
DISPLAY 0.872340 (-10775 3975);
PAINT GREEN (-10775 3975);
DISPLAY INVISIBLE (-10775 3975);
FORCEPROP 2 LAST CDS_LIB standard
J 0
(-11100 4100);
DISPLAY INVISIBLE (-11100 4100);
FORCEPROP 2 LAST PATH I24
J 0
(-11375 4150);
DISPLAY 1.021277 (-11375 4150);
DISPLAY INVISIBLE (-11375 4150);
FORCEADD OFFPAGE..1
(-11100 4475);
FORCEPROP 2 LAST $XR0 16 
J 0
(-11381 4475);
DISPLAY 0.638298 (-11381 4475);
PAINT MONO (-11381 4475);
FORCEPROP 1 LAST COMMENT_BODY TRUE
J 0
(-10975 4375);
DISPLAY 0.872340 (-10975 4375);
PAINT GREEN (-10975 4375);
DISPLAY INVISIBLE (-10975 4375);
FORCEPROP 1 LAST OFFPAGE TRUE
J 0
(-10775 4350);
DISPLAY 0.872340 (-10775 4350);
PAINT GREEN (-10775 4350);
DISPLAY INVISIBLE (-10775 4350);
FORCEPROP 2 LAST CDS_LIB standard
J 0
(-11100 4475);
DISPLAY INVISIBLE (-11100 4475);
FORCEPROP 2 LAST PATH I25
J 0
(-11375 4525);
DISPLAY 1.021277 (-11375 4525);
DISPLAY INVISIBLE (-11375 4525);
FORCEADD OFFPAGE..1
(-11100 5200);
FORCEPROP 2 LAST $XR0 16 
J 0
(-11381 5200);
DISPLAY 0.638298 (-11381 5200);
PAINT MONO (-11381 5200);
FORCEPROP 1 LAST COMMENT_BODY TRUE
J 0
(-10975 5100);
DISPLAY 0.872340 (-10975 5100);
PAINT GREEN (-10975 5100);
DISPLAY INVISIBLE (-10975 5100);
FORCEPROP 1 LAST OFFPAGE TRUE
J 0
(-10775 5075);
DISPLAY 0.872340 (-10775 5075);
PAINT GREEN (-10775 5075);
DISPLAY INVISIBLE (-10775 5075);
FORCEPROP 2 LAST CDS_LIB standard
J 0
(-11100 5200);
DISPLAY INVISIBLE (-11100 5200);
FORCEPROP 2 LAST PATH I26
J 0
(-11375 5250);
DISPLAY 1.021277 (-11375 5250);
DISPLAY INVISIBLE (-11375 5250);
FORCEADD OFFPAGE..1
(-11100 5575);
FORCEPROP 2 LAST $XR0 16 
J 0
(-11381 5575);
DISPLAY 0.638298 (-11381 5575);
PAINT MONO (-11381 5575);
FORCEPROP 1 LAST COMMENT_BODY TRUE
J 0
(-10975 5475);
DISPLAY 0.872340 (-10975 5475);
PAINT GREEN (-10975 5475);
DISPLAY INVISIBLE (-10975 5475);
FORCEPROP 1 LAST OFFPAGE TRUE
J 0
(-10775 5450);
DISPLAY 0.872340 (-10775 5450);
PAINT GREEN (-10775 5450);
DISPLAY INVISIBLE (-10775 5450);
FORCEPROP 2 LAST CDS_LIB standard
J 0
(-11100 5575);
DISPLAY INVISIBLE (-11100 5575);
FORCEPROP 2 LAST PATH I27
J 0
(-11375 5625);
DISPLAY 1.021277 (-11375 5625);
DISPLAY INVISIBLE (-11375 5625);
FORCEADD VCC15..1
(-11100 7450);
FORCEPROP 3 LASTPIN (-11100 7400) SIG_NAME PVNN_TERM_CPU0\g
J 0
(-11090 7410);
DISPLAY 0.659574 (-11090 7410);
PAINT MONO (-11090 7410);
DISPLAY INVISIBLE (-11090 7410);
FORCEPROP 1 LAST HDL_POWER PVNN_TERM_CPU0
J 1
(-11100 7500);
DISPLAY 0.617021 (-11100 7500);
PAINT GREEN (-11100 7500);
FORCEPROP 2 LAST CDS_LIB logical_power
J 0
(-11100 7450);
DISPLAY INVISIBLE (-11100 7450);
FORCEPROP 1 LAST PATH I28
J 0
(-11050 7475);
DISPLAY 0.872340 (-11050 7475);
PAINT AQUA (-11050 7475);
DISPLAY INVISIBLE (-11050 7475);
FORCEADD OFFPAGE..6
(-10550 6275);
FORCEPROP 2 LAST $XR1 278 
J 0
(-10950 6275);
DISPLAY 0.638298 (-10950 6275);
PAINT MONO (-10950 6275);
FORCEPROP 2 LAST $XR0 241 
J 0
(-10830 6275);
DISPLAY 0.638298 (-10830 6275);
PAINT MONO (-10830 6275);
FORCEPROP 1 LAST COMMENT_BODY TRUE
J 0
(-10450 6200);
DISPLAY 0.872340 (-10450 6200);
PAINT GREEN (-10450 6200);
DISPLAY INVISIBLE (-10450 6200);
FORCEPROP 1 LAST OFFPAGE TRUE
J 0
(-10225 6150);
DISPLAY 0.872340 (-10225 6150);
PAINT GREEN (-10225 6150);
DISPLAY INVISIBLE (-10225 6150);
FORCEPROP 2 LAST CDS_LIB standard
J 0
(-10550 6275);
DISPLAY INVISIBLE (-10550 6275);
FORCEPROP 2 LAST PATH I29
J 0
(-10825 6325);
DISPLAY 1.021277 (-10825 6325);
DISPLAY INVISIBLE (-10825 6325);
FORCEADD OFFPAGE..1
(-10150 3175);
FORCEPROP 2 LAST $XR0 222 
J 0
(-10402 3175);
DISPLAY 0.638298 (-10402 3175);
PAINT MONO (-10402 3175);
FORCEPROP 1 LAST COMMENT_BODY TRUE
J 0
(-10025 3075);
DISPLAY 0.872340 (-10025 3075);
PAINT GREEN (-10025 3075);
DISPLAY INVISIBLE (-10025 3075);
FORCEPROP 1 LAST OFFPAGE TRUE
J 0
(-9825 3050);
DISPLAY 0.872340 (-9825 3050);
PAINT GREEN (-9825 3050);
DISPLAY INVISIBLE (-9825 3050);
FORCEPROP 2 LAST CDS_LIB standard
J 0
(-10150 3175);
DISPLAY INVISIBLE (-10150 3175);
FORCEPROP 2 LAST PATH I3
J 0
(-10400 3225);
DISPLAY 1.021277 (-10400 3225);
DISPLAY INVISIBLE (-10400 3225);
FORCEADD OFFPAGE..1
(-10550 6425);
FORCEPROP 2 LAST $XR1 278 
J 0
(-10952 6425);
DISPLAY 0.638298 (-10952 6425);
PAINT MONO (-10952 6425);
FORCEPROP 2 LAST $XR0 241 
J 0
(-10832 6425);
DISPLAY 0.638298 (-10832 6425);
PAINT MONO (-10832 6425);
FORCEPROP 1 LAST COMMENT_BODY TRUE
J 0
(-10425 6325);
DISPLAY 0.872340 (-10425 6325);
PAINT GREEN (-10425 6325);
DISPLAY INVISIBLE (-10425 6325);
FORCEPROP 1 LAST OFFPAGE TRUE
J 0
(-10225 6300);
DISPLAY 0.872340 (-10225 6300);
PAINT GREEN (-10225 6300);
DISPLAY INVISIBLE (-10225 6300);
FORCEPROP 2 LAST CDS_LIB standard
J 0
(-10550 6425);
DISPLAY INVISIBLE (-10550 6425);
FORCEPROP 2 LAST PATH I30
J 0
(-10825 6475);
DISPLAY 1.021277 (-10825 6475);
DISPLAY INVISIBLE (-10825 6475);
FORCEADD OFFPAGE..5
(-10500 6825);
FORCEPROP 2 LAST $XR1 266 
J 0
(-10874 6825);
DISPLAY 0.638298 (-10874 6825);
PAINT MONO (-10874 6825);
FORCEPROP 2 LAST $XR0 14 
J 0
(-10754 6825);
DISPLAY 0.638298 (-10754 6825);
PAINT MONO (-10754 6825);
FORCEPROP 1 LAST COMMENT_BODY TRUE
J 0
(-10400 6750);
DISPLAY 0.872340 (-10400 6750);
PAINT GREEN (-10400 6750);
DISPLAY INVISIBLE (-10400 6750);
FORCEPROP 1 LAST OFFPAGE TRUE
J 0
(-10175 6700);
DISPLAY 0.872340 (-10175 6700);
PAINT GREEN (-10175 6700);
DISPLAY INVISIBLE (-10175 6700);
FORCEPROP 2 LAST CDS_LIB standard
J 0
(-10500 6825);
DISPLAY INVISIBLE (-10500 6825);
FORCEPROP 2 LAST PATH I31
J 0
(-10750 6875);
DISPLAY 1.021277 (-10750 6875);
DISPLAY INVISIBLE (-10750 6875);
FORCEADD OFFPAGE..1
(-10500 7125);
FORCEPROP 2 LAST $XR1 266 
J 0
(-10841 7125);
DISPLAY 0.638298 (-10841 7125);
PAINT MONO (-10841 7125);
FORCEPROP 2 LAST $XR0 14 
J 0
(-10721 7125);
DISPLAY 0.638298 (-10721 7125);
PAINT MONO (-10721 7125);
FORCEPROP 1 LAST COMMENT_BODY TRUE
J 0
(-10375 7025);
DISPLAY 0.872340 (-10375 7025);
PAINT GREEN (-10375 7025);
DISPLAY INVISIBLE (-10375 7025);
FORCEPROP 1 LAST OFFPAGE TRUE
J 0
(-10175 7000);
DISPLAY 0.872340 (-10175 7000);
PAINT GREEN (-10175 7000);
DISPLAY INVISIBLE (-10175 7000);
FORCEPROP 2 LAST CDS_LIB standard
J 0
(-10500 7125);
DISPLAY INVISIBLE (-10500 7125);
FORCEPROP 2 LAST PATH I32
J 0
(-10700 7175);
DISPLAY 1.021277 (-10700 7175);
DISPLAY INVISIBLE (-10700 7175);
FORCEADD OFFPAGE..6
(-10500 6975);
FORCEPROP 2 LAST $XR1 266 
J 0
(-10869 6975);
DISPLAY 0.638298 (-10869 6975);
PAINT MONO (-10869 6975);
FORCEPROP 2 LAST $XR0 14 
J 0
(-10749 6975);
DISPLAY 0.638298 (-10749 6975);
PAINT MONO (-10749 6975);
FORCEPROP 1 LAST COMMENT_BODY TRUE
J 0
(-10400 6900);
DISPLAY 0.872340 (-10400 6900);
PAINT GREEN (-10400 6900);
DISPLAY INVISIBLE (-10400 6900);
FORCEPROP 1 LAST OFFPAGE TRUE
J 0
(-10175 6850);
DISPLAY 0.872340 (-10175 6850);
PAINT GREEN (-10175 6850);
DISPLAY INVISIBLE (-10175 6850);
FORCEPROP 2 LAST CDS_LIB standard
J 0
(-10500 6975);
DISPLAY INVISIBLE (-10500 6975);
FORCEPROP 2 LAST PATH I33
J 0
(-10725 7025);
DISPLAY 1.021277 (-10725 7025);
DISPLAY INVISIBLE (-10725 7025);
FORCEADD OFFPAGE..1
(-10500 7425);
FORCEPROP 2 LAST $XR0 222 
J 0
(-10752 7425);
DISPLAY 0.638298 (-10752 7425);
PAINT MONO (-10752 7425);
FORCEPROP 1 LAST COMMENT_BODY TRUE
J 0
(-10375 7325);
DISPLAY 0.872340 (-10375 7325);
PAINT GREEN (-10375 7325);
DISPLAY INVISIBLE (-10375 7325);
FORCEPROP 1 LAST OFFPAGE TRUE
J 0
(-10175 7300);
DISPLAY 0.872340 (-10175 7300);
PAINT GREEN (-10175 7300);
DISPLAY INVISIBLE (-10175 7300);
FORCEPROP 2 LAST CDS_LIB standard
J 0
(-10500 7425);
DISPLAY INVISIBLE (-10500 7425);
FORCEPROP 2 LAST PATH I34
J 0
(-10750 7475);
DISPLAY 1.021277 (-10750 7475);
DISPLAY INVISIBLE (-10750 7475);
FORCEADD OFFPAGE..5
(-10500 7575);
FORCEPROP 2 LAST $XR1 253 
J 0
(-10905 7575);
DISPLAY 0.638298 (-10905 7575);
PAINT MONO (-10905 7575);
FORCEPROP 2 LAST $XR0 214 
J 0
(-10785 7575);
DISPLAY 0.638298 (-10785 7575);
PAINT MONO (-10785 7575);
FORCEPROP 1 LAST COMMENT_BODY TRUE
J 0
(-10400 7500);
DISPLAY 0.872340 (-10400 7500);
PAINT GREEN (-10400 7500);
DISPLAY INVISIBLE (-10400 7500);
FORCEPROP 1 LAST OFFPAGE TRUE
J 0
(-10175 7450);
DISPLAY 0.872340 (-10175 7450);
PAINT GREEN (-10175 7450);
DISPLAY INVISIBLE (-10175 7450);
FORCEPROP 2 LAST CDS_LIB standard
J 0
(-10500 7575);
DISPLAY INVISIBLE (-10500 7575);
FORCEPROP 2 LAST PATH I35
J 0
(-10775 7625);
DISPLAY 1.021277 (-10775 7625);
DISPLAY INVISIBLE (-10775 7625);
FORCEADD Q_RES..1
(-10375 7325);
FORCEPROP 1 LAST PART_NUMBER CS04992FB07
J 0
(-10250 7350);
DISPLAY 0.489362 (-10250 7350);
PAINT BLUE (-10250 7350);
DISPLAY INVISIBLE (-10250 7350);
FORCEPROP 1 LAST VALUE 49.9
J 2
(-10100 7325);
DISPLAY 0.489362 (-10100 7325);
PAINT SKYBLUE (-10100 7325);
FORCEPROP 1 LAST TOLERANCE 1%
J 0
(-10175 7325);
DISPLAY 0.489362 (-10175 7325);
PAINT SKYBLUE (-10175 7325);
FORCEPROP 1 LAST PACK_TYPE 0402LF
J 0
(-10250 7375);
DISPLAY 0.489362 (-10250 7375);
PAINT SKYBLUE (-10250 7375);
FORCEPROP 1 LAST WATTAGE 1/16W
J 2
(-9875 7375);
DISPLAY 0.489362 (-9875 7375);
PAINT SKYBLUE (-9875 7375);
FORCEPROP 1 LAST MATERIAL EMPTY
J 0
(-10100 7325);
DISPLAY 0.489362 (-10100 7325);
PAINT RED (-10100 7325);
FORCEPROP 1 LAST LOCATION R2322
J 0
(-10625 7325);
DISPLAY 0.723404 (-10625 7325);
PAINT AQUA (-10625 7325);
FORCEPROP 1 LASTPIN (-10475 7325) $PN 1
J 0
(-10463 7337);
DISPLAY 0.617021 (-10463 7337);
PAINT MONO (-10463 7337);
FORCEPROP 1 LASTPIN (-10275 7325) $PN 2
J 0
(-10313 7337);
DISPLAY 0.617021 (-10313 7337);
PAINT MONO (-10313 7337);
FORCEPROP 2 LAST CDS_LIB pure_quanta
J 0
(-10375 7325);
DISPLAY INVISIBLE (-10375 7325);
FORCEPROP 1 LAST PATH I36
J 0
(-10425 7475);
DISPLAY 0.978723 (-10425 7475);
PAINT WHITE (-10425 7475);
DISPLAY INVISIBLE (-10425 7475);
FORCEPROP 0 LAST $SEC 1
J 0
(-10050 7400);
DISPLAY 0.680851 (-10050 7400);
PAINT MONO (-10050 7400);
DISPLAY INVISIBLE (-10050 7400);
FORCEPROP 0 LAST CDS_SEC 1
J 0
(-10050 7400);
DISPLAY 1.021277 (-10050 7400);
DISPLAY INVISIBLE (-10050 7400);
FORCEADD Q_RES..1
(-10375 7225);
FORCEPROP 1 LAST PART_NUMBER CS11002FB07
J 0
(-10250 7250);
DISPLAY 0.489362 (-10250 7250);
PAINT BLUE (-10250 7250);
DISPLAY INVISIBLE (-10250 7250);
FORCEPROP 1 LAST VALUE 100
J 2
(-10200 7225);
DISPLAY 0.489362 (-10200 7225);
PAINT SKYBLUE (-10200 7225);
FORCEPROP 1 LAST TOLERANCE 1%
J 0
(-10175 7225);
DISPLAY 0.489362 (-10175 7225);
PAINT SKYBLUE (-10175 7225);
FORCEPROP 1 LAST PACK_TYPE 0402LF
J 0
(-10250 7275);
DISPLAY 0.489362 (-10250 7275);
PAINT SKYBLUE (-10250 7275);
FORCEPROP 1 LAST WATTAGE 1/16W
J 2
(-9875 7275);
DISPLAY 0.489362 (-9875 7275);
PAINT SKYBLUE (-9875 7275);
FORCEPROP 1 LAST MATERIAL EMPTY
J 0
(-10100 7225);
DISPLAY 0.489362 (-10100 7225);
PAINT RED (-10100 7225);
FORCEPROP 1 LAST LOCATION R2386
J 0
(-10625 7225);
DISPLAY 0.723404 (-10625 7225);
PAINT AQUA (-10625 7225);
FORCEPROP 1 LASTPIN (-10475 7225) $PN 1
J 0
(-10463 7237);
DISPLAY 0.617021 (-10463 7237);
FORCEPROP 1 LASTPIN (-10275 7225) $PN 2
J 0
(-10313 7237);
DISPLAY 0.617021 (-10313 7237);
FORCEPROP 2 LAST CDS_LIB pure_quanta
J 0
(-10375 7225);
PAINT MONO (-10375 7225);
DISPLAY INVISIBLE (-10375 7225);
FORCEPROP 1 LAST PATH I37
J 0
(-10425 7375);
DISPLAY 0.978723 (-10425 7375);
PAINT WHITE (-10425 7375);
DISPLAY INVISIBLE (-10425 7375);
FORCEPROP 2 LAST $SEC 1
J 0
(-10425 7425);
DISPLAY 0.680851 (-10425 7425);
PAINT MONO (-10425 7425);
DISPLAY INVISIBLE (-10425 7425);
FORCEPROP 2 LAST CDS_SEC 1
J 0
(-10425 7425);
DISPLAY 1.021277 (-10425 7425);
DISPLAY INVISIBLE (-10425 7425);
FORCEADD Q_RES..1
(-9875 3950);
FORCEPROP 1 LAST PART_NUMBER CS11002FB07
J 0
(-9750 4000);
DISPLAY 0.617021 (-9750 4000);
PAINT BLUE (-9750 4000);
DISPLAY INVISIBLE (-9750 4000);
FORCEPROP 1 LAST WATTAGE 1/16W
J 2
(-9450 4050);
DISPLAY 0.617021 (-9450 4050);
PAINT SKYBLUE (-9450 4050);
FORCEPROP 1 LAST TOLERANCE 1%
J 0
(-9650 3950);
DISPLAY 0.617021 (-9650 3950);
PAINT SKYBLUE (-9650 3950);
FORCEPROP 1 LAST VALUE 100
J 2
(-9675 3950);
DISPLAY 0.617021 (-9675 3950);
PAINT SKYBLUE (-9675 3950);
FORCEPROP 1 LAST PACK_TYPE 0402LF
J 0
(-9575 3950);
DISPLAY 0.617021 (-9575 3950);
PAINT SKYBLUE (-9575 3950);
FORCEPROP 1 LAST MATERIAL CHIP
J 0
(-9750 4050);
DISPLAY 0.617021 (-9750 4050);
PAINT SKYBLUE (-9750 4050);
FORCEPROP 1 LAST LOCATION PR520
J 0
(-10075 3950);
DISPLAY 0.617021 (-10075 3950);
PAINT AQUA (-10075 3950);
FORCEPROP 1 LASTPIN (-9975 3950) $PN 1
J 0
(-9963 3962);
DISPLAY 0.617021 (-9963 3962);
FORCEPROP 1 LASTPIN (-9775 3950) $PN 2
J 0
(-9813 3962);
DISPLAY 0.617021 (-9813 3962);
FORCEPROP 2 LAST CDS_LIB pure_quanta
J 0
(-9875 3950);
PAINT MONO (-9875 3950);
DISPLAY INVISIBLE (-9875 3950);
FORCEPROP 1 LAST PATH I38
J 0
(-9925 4100);
DISPLAY 0.978723 (-9925 4100);
PAINT WHITE (-9925 4100);
DISPLAY INVISIBLE (-9925 4100);
FORCEPROP 2 LAST $SEC 1
J 0
(-9925 4150);
DISPLAY 0.680851 (-9925 4150);
PAINT MONO (-9925 4150);
DISPLAY INVISIBLE (-9925 4150);
FORCEPROP 2 LAST CDS_SEC 1
J 0
(-9925 4150);
DISPLAY 1.021277 (-9925 4150);
DISPLAY INVISIBLE (-9925 4150);
FORCEADD Q_SHORT..1
(-9900 4475);
FORCEPROP 1 LAST PART_NUMBER SHORT6
J 0
(-9875 4235);
DISPLAY 0.617021 (-9875 4235);
PAINT BLUE (-9875 4235);
DISPLAY INVISIBLE (-9875 4235);
FORCEPROP 2 LAST PACK_TYPE SM
J 0
(-9875 4325);
DISPLAY 0.617021 (-9875 4325);
PAINT SKYBLUE (-9875 4325);
FORCEPROP 1 LAST MATERIAL EMPTY
J 0
(-9875 4285);
DISPLAY 0.617021 (-9875 4285);
PAINT RED (-9875 4285);
FORCEPROP 1 LAST LOCATION PJ46
J 0
(-10000 4330);
DISPLAY 0.617021 (-10000 4330);
PAINT AQUA (-10000 4330);
FORCEPROP 0 LASTPIN (-10025 4475) $PN 1
J 2
(-10035 4485);
DISPLAY 0.617021 (-10035 4485);
PAINT MONO (-10035 4485);
FORCEPROP 0 LASTPIN (-9775 4475) $PN 2
J 0
(-9765 4485);
DISPLAY 0.617021 (-9765 4485);
PAINT MONO (-9765 4485);
FORCEPROP 2 LAST CDS_LIB pure_quanta
J 0
(-9900 4475);
DISPLAY INVISIBLE (-9900 4475);
FORCEPROP 1 LAST NEEDS_NO_SIZE TRUE
J 0
(-9900 4475);
DISPLAY 0.468085 (-9900 4475);
PAINT GREEN (-9900 4475);
DISPLAY INVISIBLE (-9900 4475);
FORCEPROP 1 LAST PATH I39
J 0
(-9975 4680);
DISPLAY 0.723404 (-9975 4680);
PAINT GREEN (-9975 4680);
DISPLAY INVISIBLE (-9975 4680);
FORCEPROP 1 LAST LOCATION PJ46
J 0
(-9975 4725);
DISPLAY 1.021277 (-9975 4725);
PAINT AQUA (-9975 4725);
DISPLAY INVISIBLE (-9975 4725);
FORCEPROP 0 LAST $SEC 1
J 0
(-9975 4725);
DISPLAY 0.680851 (-9975 4725);
PAINT MONO (-9975 4725);
DISPLAY INVISIBLE (-9975 4725);
FORCEPROP 0 LAST CDS_SEC 1
J 0
(-9975 4725);
DISPLAY 1.021277 (-9975 4725);
DISPLAY INVISIBLE (-9975 4725);
FORCEADD UNIVERSAL_GND..1
(-8500 1625);
FORCEPROP 3 LASTPIN (-8500 1675) SIG_NAME GND\g
J 0
(-8490 1685);
DISPLAY 0.659574 (-8490 1685);
PAINT MONO (-8490 1685);
DISPLAY INVISIBLE (-8490 1685);
FORCEPROP 1 LAST HDL_POWER GND
J 1
(-8475 1550);
DISPLAY 0.872340 (-8475 1550);
PAINT GREEN (-8475 1550);
DISPLAY INVISIBLE (-8475 1550);
FORCEPROP 2 LAST CDS_LIB logical_power
J 0
(-8500 1625);
PAINT MONO (-8500 1625);
DISPLAY INVISIBLE (-8500 1625);
FORCEPROP 1 LAST PATH I4
J 0
(-8425 1625);
DISPLAY 0.872340 (-8425 1625);
PAINT AQUA (-8425 1625);
DISPLAY INVISIBLE (-8425 1625);
FORCEADD Q_RES..1
(-9825 4625);
FORCEPROP 1 LAST PART_NUMBER CS11002FB07
J 0
(-9700 4675);
DISPLAY 0.617021 (-9700 4675);
PAINT BLUE (-9700 4675);
DISPLAY INVISIBLE (-9700 4675);
FORCEPROP 1 LAST WATTAGE 1/16W
J 2
(-9400 4725);
DISPLAY 0.617021 (-9400 4725);
PAINT SKYBLUE (-9400 4725);
FORCEPROP 1 LAST PACK_TYPE 0402LF
J 0
(-9525 4625);
DISPLAY 0.617021 (-9525 4625);
PAINT SKYBLUE (-9525 4625);
FORCEPROP 1 LAST MATERIAL CHIP
J 0
(-9700 4725);
DISPLAY 0.617021 (-9700 4725);
PAINT SKYBLUE (-9700 4725);
FORCEPROP 1 LAST TOLERANCE 1%
J 0
(-9600 4625);
DISPLAY 0.617021 (-9600 4625);
PAINT SKYBLUE (-9600 4625);
FORCEPROP 1 LAST VALUE 100
J 2
(-9625 4625);
DISPLAY 0.617021 (-9625 4625);
PAINT SKYBLUE (-9625 4625);
FORCEPROP 1 LAST LOCATION PR522
J 0
(-10025 4625);
DISPLAY 0.617021 (-10025 4625);
PAINT AQUA (-10025 4625);
FORCEPROP 1 LASTPIN (-9925 4625) $PN 1
J 0
(-9913 4637);
DISPLAY 0.617021 (-9913 4637);
FORCEPROP 1 LASTPIN (-9725 4625) $PN 2
J 0
(-9763 4637);
DISPLAY 0.617021 (-9763 4637);
FORCEPROP 2 LAST CDS_LIB pure_quanta
J 0
(-9825 4625);
PAINT MONO (-9825 4625);
DISPLAY INVISIBLE (-9825 4625);
FORCEPROP 1 LAST PATH I40
J 0
(-9875 4775);
DISPLAY 0.978723 (-9875 4775);
PAINT WHITE (-9875 4775);
DISPLAY INVISIBLE (-9875 4775);
FORCEPROP 2 LAST $SEC 1
J 0
(-9875 4825);
DISPLAY 0.680851 (-9875 4825);
PAINT MONO (-9875 4825);
DISPLAY INVISIBLE (-9875 4825);
FORCEPROP 2 LAST CDS_SEC 1
J 0
(-9875 4825);
DISPLAY 1.021277 (-9875 4825);
DISPLAY INVISIBLE (-9875 4825);
FORCEADD VCC15..1
(-9325 4775);
FORCEPROP 3 LASTPIN (-9325 4725) SIG_NAME PVCCFA_EHV_CPU0\g
J 0
(-9315 4735);
DISPLAY 0.659574 (-9315 4735);
PAINT MONO (-9315 4735);
DISPLAY INVISIBLE (-9315 4735);
FORCEPROP 1 LAST HDL_POWER PVCCFA_EHV_CPU0
J 1
(-9325 4825);
DISPLAY 0.617021 (-9325 4825);
PAINT GREEN (-9325 4825);
FORCEPROP 2 LAST CDS_LIB logical_power
J 0
(-9325 4775);
PAINT MONO (-9325 4775);
DISPLAY INVISIBLE (-9325 4775);
FORCEPROP 1 LAST PATH I41
J 0
(-9275 4800);
DISPLAY 0.872340 (-9275 4800);
PAINT AQUA (-9275 4800);
DISPLAY INVISIBLE (-9275 4800);
FORCEADD Q_RES..1
(-9875 5050);
FORCEPROP 1 LAST PART_NUMBER CS11002FB07
J 0
(-9750 5100);
DISPLAY 0.617021 (-9750 5100);
PAINT BLUE (-9750 5100);
DISPLAY INVISIBLE (-9750 5100);
FORCEPROP 1 LAST WATTAGE 1/16W
J 2
(-9450 5150);
DISPLAY 0.617021 (-9450 5150);
PAINT SKYBLUE (-9450 5150);
FORCEPROP 1 LAST PACK_TYPE 0402LF
J 0
(-9575 5050);
DISPLAY 0.617021 (-9575 5050);
PAINT SKYBLUE (-9575 5050);
FORCEPROP 1 LAST TOLERANCE 1%
J 0
(-9650 5050);
DISPLAY 0.617021 (-9650 5050);
PAINT SKYBLUE (-9650 5050);
FORCEPROP 1 LAST VALUE 100
J 2
(-9675 5050);
DISPLAY 0.617021 (-9675 5050);
PAINT SKYBLUE (-9675 5050);
FORCEPROP 1 LAST MATERIAL CHIP
J 0
(-9750 5150);
DISPLAY 0.617021 (-9750 5150);
PAINT SKYBLUE (-9750 5150);
FORCEPROP 1 LAST LOCATION PR519
J 0
(-10075 5050);
DISPLAY 0.617021 (-10075 5050);
PAINT AQUA (-10075 5050);
FORCEPROP 1 LASTPIN (-9975 5050) $PN 1
J 0
(-9963 5062);
DISPLAY 0.617021 (-9963 5062);
FORCEPROP 1 LASTPIN (-9775 5050) $PN 2
J 0
(-9813 5062);
DISPLAY 0.617021 (-9813 5062);
FORCEPROP 2 LAST CDS_LIB pure_quanta
J 0
(-9875 5050);
PAINT MONO (-9875 5050);
DISPLAY INVISIBLE (-9875 5050);
FORCEPROP 1 LAST PATH I42
J 0
(-9925 5200);
DISPLAY 0.978723 (-9925 5200);
PAINT WHITE (-9925 5200);
DISPLAY INVISIBLE (-9925 5200);
FORCEPROP 2 LAST $SEC 1
J 0
(-9925 5250);
DISPLAY 0.680851 (-9925 5250);
PAINT MONO (-9925 5250);
DISPLAY INVISIBLE (-9925 5250);
FORCEPROP 2 LAST CDS_SEC 1
J 0
(-9925 5250);
DISPLAY 1.021277 (-9925 5250);
DISPLAY INVISIBLE (-9925 5250);
FORCEADD Q_SHORT..1
(-9900 5575);
FORCEPROP 1 LAST PART_NUMBER SHORT6
J 0
(-9875 5335);
DISPLAY 0.617021 (-9875 5335);
PAINT BLUE (-9875 5335);
DISPLAY INVISIBLE (-9875 5335);
FORCEPROP 1 LAST MATERIAL EMPTY
J 0
(-9875 5385);
DISPLAY 0.617021 (-9875 5385);
PAINT RED (-9875 5385);
FORCEPROP 2 LAST PACK_TYPE SM
J 0
(-9875 5425);
DISPLAY 0.617021 (-9875 5425);
PAINT SKYBLUE (-9875 5425);
FORCEPROP 1 LAST LOCATION PJ45
J 0
(-10000 5430);
DISPLAY 0.617021 (-10000 5430);
PAINT AQUA (-10000 5430);
FORCEPROP 0 LASTPIN (-10025 5575) $PN 1
J 2
(-10035 5585);
DISPLAY 0.617021 (-10035 5585);
PAINT MONO (-10035 5585);
FORCEPROP 0 LASTPIN (-9775 5575) $PN 2
J 0
(-9765 5585);
DISPLAY 0.617021 (-9765 5585);
PAINT MONO (-9765 5585);
FORCEPROP 2 LAST CDS_LIB pure_quanta
J 0
(-9900 5575);
DISPLAY INVISIBLE (-9900 5575);
FORCEPROP 1 LAST NEEDS_NO_SIZE TRUE
J 0
(-9900 5575);
DISPLAY 0.468085 (-9900 5575);
PAINT GREEN (-9900 5575);
DISPLAY INVISIBLE (-9900 5575);
FORCEPROP 1 LAST PATH I43
J 0
(-9975 5780);
DISPLAY 0.723404 (-9975 5780);
PAINT GREEN (-9975 5780);
DISPLAY INVISIBLE (-9975 5780);
FORCEPROP 1 LAST LOCATION PJ45
J 0
(-9975 5825);
DISPLAY 1.021277 (-9975 5825);
PAINT AQUA (-9975 5825);
DISPLAY INVISIBLE (-9975 5825);
FORCEPROP 0 LAST $SEC 1
J 0
(-9975 5825);
DISPLAY 0.680851 (-9975 5825);
PAINT MONO (-9975 5825);
DISPLAY INVISIBLE (-9975 5825);
FORCEPROP 0 LAST CDS_SEC 1
J 0
(-9975 5825);
DISPLAY 1.021277 (-9975 5825);
DISPLAY INVISIBLE (-9975 5825);
FORCEADD Q_RES..1
(-9825 5725);
FORCEPROP 1 LAST PART_NUMBER CS11002FB07
J 0
(-9700 5775);
DISPLAY 0.617021 (-9700 5775);
PAINT BLUE (-9700 5775);
DISPLAY INVISIBLE (-9700 5775);
FORCEPROP 1 LAST PACK_TYPE 0402LF
J 0
(-9525 5725);
DISPLAY 0.617021 (-9525 5725);
PAINT SKYBLUE (-9525 5725);
FORCEPROP 1 LAST VALUE 100
J 2
(-9625 5725);
DISPLAY 0.617021 (-9625 5725);
PAINT SKYBLUE (-9625 5725);
FORCEPROP 1 LAST TOLERANCE 1%
J 0
(-9600 5725);
DISPLAY 0.617021 (-9600 5725);
PAINT SKYBLUE (-9600 5725);
FORCEPROP 1 LAST WATTAGE 1/16W
J 2
(-9425 5825);
DISPLAY 0.617021 (-9425 5825);
PAINT SKYBLUE (-9425 5825);
FORCEPROP 1 LAST MATERIAL CHIP
J 0
(-9700 5825);
DISPLAY 0.617021 (-9700 5825);
PAINT SKYBLUE (-9700 5825);
FORCEPROP 1 LAST LOCATION PR521
J 0
(-10025 5725);
DISPLAY 0.617021 (-10025 5725);
PAINT AQUA (-10025 5725);
FORCEPROP 1 LASTPIN (-9925 5725) $PN 1
J 0
(-9913 5737);
DISPLAY 0.617021 (-9913 5737);
FORCEPROP 1 LASTPIN (-9725 5725) $PN 2
J 0
(-9763 5737);
DISPLAY 0.617021 (-9763 5737);
FORCEPROP 2 LAST CDS_LIB pure_quanta
J 0
(-9825 5725);
PAINT MONO (-9825 5725);
DISPLAY INVISIBLE (-9825 5725);
FORCEPROP 1 LAST PATH I44
J 0
(-9875 5875);
DISPLAY 0.978723 (-9875 5875);
PAINT WHITE (-9875 5875);
DISPLAY INVISIBLE (-9875 5875);
FORCEPROP 2 LAST $SEC 1
J 0
(-9875 5925);
DISPLAY 0.680851 (-9875 5925);
PAINT MONO (-9875 5925);
DISPLAY INVISIBLE (-9875 5925);
FORCEPROP 2 LAST CDS_SEC 1
J 0
(-9875 5925);
DISPLAY 1.021277 (-9875 5925);
DISPLAY INVISIBLE (-9875 5925);
FORCEADD UNIVERSAL_GND..1
(-9350 4950);
FORCEPROP 3 LASTPIN (-9350 5000) SIG_NAME GND\g
J 0
(-9340 5010);
DISPLAY 0.659574 (-9340 5010);
PAINT MONO (-9340 5010);
DISPLAY INVISIBLE (-9340 5010);
FORCEPROP 1 LAST HDL_POWER GND
J 1
(-9325 4875);
DISPLAY 0.872340 (-9325 4875);
PAINT GREEN (-9325 4875);
DISPLAY INVISIBLE (-9325 4875);
FORCEPROP 2 LAST CDS_LIB logical_power
J 0
(-9350 4950);
PAINT MONO (-9350 4950);
DISPLAY INVISIBLE (-9350 4950);
FORCEPROP 1 LAST PATH I45
J 0
(-9275 4950);
DISPLAY 0.872340 (-9275 4950);
PAINT AQUA (-9275 4950);
DISPLAY INVISIBLE (-9275 4950);
FORCEADD VCC15..1
(-9325 5875);
FORCEPROP 3 LASTPIN (-9325 5825) SIG_NAME PVCCINFAON_CPU0\g
J 0
(-9315 5835);
DISPLAY 0.659574 (-9315 5835);
PAINT MONO (-9315 5835);
DISPLAY INVISIBLE (-9315 5835);
FORCEPROP 1 LAST HDL_POWER PVCCINFAON_CPU0
J 1
(-9325 5925);
DISPLAY 0.617021 (-9325 5925);
PAINT GREEN (-9325 5925);
FORCEPROP 2 LAST CDS_LIB logical_power
J 0
(-9325 5875);
DISPLAY INVISIBLE (-9325 5875);
FORCEPROP 1 LAST PATH I46
J 0
(-9275 5900);
DISPLAY 0.872340 (-9275 5900);
PAINT AQUA (-9275 5900);
DISPLAY INVISIBLE (-9275 5900);
FORCEADD Q_RES..1
(-8850 4475);
FORCEPROP 1 LAST PART_NUMBER CS00002JB13
J 0
(-8725 4525);
DISPLAY 0.617021 (-8725 4525);
PAINT BLUE (-8725 4525);
DISPLAY INVISIBLE (-8725 4525);
FORCEPROP 1 LAST VALUE 0
J 2
(-8700 4475);
DISPLAY 0.617021 (-8700 4475);
PAINT SKYBLUE (-8700 4475);
FORCEPROP 1 LAST TOLERANCE 5%
J 0
(-8675 4475);
DISPLAY 0.617021 (-8675 4475);
PAINT SKYBLUE (-8675 4475);
FORCEPROP 1 LAST MATERIAL CHIP
J 0
(-8725 4575);
DISPLAY 0.617021 (-8725 4575);
PAINT SKYBLUE (-8725 4575);
FORCEPROP 1 LAST PACK_TYPE 0402LF
J 0
(-8600 4475);
DISPLAY 0.617021 (-8600 4475);
PAINT SKYBLUE (-8600 4475);
FORCEPROP 1 LAST WATTAGE 1/16W
J 2
(-8425 4575);
DISPLAY 0.617021 (-8425 4575);
PAINT SKYBLUE (-8425 4575);
FORCEPROP 1 LAST LOCATION PR121
J 0
(-9050 4475);
DISPLAY 0.617021 (-9050 4475);
PAINT AQUA (-9050 4475);
FORCEPROP 1 LASTPIN (-8950 4475) $PN 1
J 0
(-8938 4487);
DISPLAY 0.617021 (-8938 4487);
PAINT MONO (-8938 4487);
FORCEPROP 1 LASTPIN (-8750 4475) $PN 2
J 0
(-8788 4487);
DISPLAY 0.617021 (-8788 4487);
PAINT MONO (-8788 4487);
FORCEPROP 2 LAST CDS_LIB pure_quanta
J 0
(-8850 4475);
DISPLAY INVISIBLE (-8850 4475);
FORCEPROP 1 LAST PATH I47
J 0
(-8900 4625);
DISPLAY 0.978723 (-8900 4625);
PAINT WHITE (-8900 4625);
DISPLAY INVISIBLE (-8900 4625);
FORCEPROP 1 LAST LOCATION PR121
J 0
(-8900 4575);
DISPLAY 1.021277 (-8900 4575);
PAINT AQUA (-8900 4575);
DISPLAY INVISIBLE (-8900 4575);
FORCEPROP 0 LAST $SEC 1
J 0
(-8900 4575);
DISPLAY 0.680851 (-8900 4575);
PAINT MONO (-8900 4575);
DISPLAY INVISIBLE (-8900 4575);
FORCEPROP 0 LAST CDS_SEC 1
J 0
(-8900 4575);
DISPLAY 1.021277 (-8900 4575);
DISPLAY INVISIBLE (-8900 4575);
FORCEADD Q_CAP..1
(-8400 4300);
FORCEPROP 1 LAST PART_NUMBER TMP_QCH2336K1B12
J 0
(-8350 4125);
DISPLAY 0.617021 (-8350 4125);
PAINT BLUE (-8350 4125);
DISPLAY INVISIBLE (-8350 4125);
FORCEPROP 1 LAST MATERIAL X7R
J 0
(-8350 4225);
DISPLAY 0.617021 (-8350 4225);
PAINT SKYBLUE (-8350 4225);
FORCEPROP 1 LAST TOLERANCE 10%
J 0
(-8350 4275);
DISPLAY 0.617021 (-8350 4275);
PAINT SKYBLUE (-8350 4275);
FORCEPROP 1 LAST VALUE 3300PF
J 0
(-8350 4375);
DISPLAY 0.617021 (-8350 4375);
PAINT SKYBLUE (-8350 4375);
FORCEPROP 1 LAST VOLTAGE 50V
J 0
(-8350 4325);
DISPLAY 0.617021 (-8350 4325);
PAINT SKYBLUE (-8350 4325);
FORCEPROP 1 LAST PACK_TYPE 0402
J 0
(-8350 4175);
DISPLAY 0.617021 (-8350 4175);
PAINT SKYBLUE (-8350 4175);
FORCEPROP 1 LAST LOCATION PC216
J 0
(-8350 4425);
DISPLAY 0.617021 (-8350 4425);
PAINT AQUA (-8350 4425);
FORCEPROP 1 LASTPIN (-8400 4400) $PN 1
J 0
(-8390 4380);
DISPLAY 0.617021 (-8390 4380);
PAINT MONO (-8390 4380);
FORCEPROP 1 LASTPIN (-8400 4200) $PN 2
J 0
(-8390 4180);
DISPLAY 0.617021 (-8390 4180);
PAINT MONO (-8390 4180);
FORCEPROP 2 LAST CDS_LIB pure_quanta
J 0
(-8400 4300);
DISPLAY INVISIBLE (-8400 4300);
FORCEPROP 1 LAST PATH I48
J 0
(-8350 4450);
DISPLAY 0.978723 (-8350 4450);
PAINT WHITE (-8350 4450);
DISPLAY INVISIBLE (-8350 4450);
FORCEPROP 1 LAST LOCATION PC216
J 0
(-8350 4425);
DISPLAY 1.021277 (-8350 4425);
PAINT AQUA (-8350 4425);
DISPLAY INVISIBLE (-8350 4425);
FORCEPROP 0 LAST $SEC 1
J 0
(-8350 4425);
DISPLAY 0.680851 (-8350 4425);
PAINT MONO (-8350 4425);
DISPLAY INVISIBLE (-8350 4425);
FORCEPROP 0 LAST CDS_SEC 1
J 0
(-8350 4425);
DISPLAY 1.021277 (-8350 4425);
DISPLAY INVISIBLE (-8350 4425);
FORCEADD Q_RES..1
(-8850 5575);
FORCEPROP 1 LAST PART_NUMBER CS00002JB13
J 0
(-8725 5625);
DISPLAY 0.617021 (-8725 5625);
PAINT BLUE (-8725 5625);
DISPLAY INVISIBLE (-8725 5625);
FORCEPROP 1 LAST MATERIAL CHIP
J 0
(-8725 5675);
DISPLAY 0.617021 (-8725 5675);
PAINT SKYBLUE (-8725 5675);
FORCEPROP 1 LAST VALUE 0
J 2
(-8700 5575);
DISPLAY 0.617021 (-8700 5575);
PAINT SKYBLUE (-8700 5575);
FORCEPROP 1 LAST PACK_TYPE 0402LF
J 0
(-8600 5575);
DISPLAY 0.617021 (-8600 5575);
PAINT SKYBLUE (-8600 5575);
FORCEPROP 1 LAST WATTAGE 1/16W
J 2
(-8425 5675);
DISPLAY 0.617021 (-8425 5675);
PAINT SKYBLUE (-8425 5675);
FORCEPROP 1 LAST TOLERANCE 5%
J 0
(-8675 5575);
DISPLAY 0.617021 (-8675 5575);
PAINT SKYBLUE (-8675 5575);
FORCEPROP 1 LAST LOCATION PR120
J 0
(-9050 5575);
DISPLAY 0.617021 (-9050 5575);
PAINT AQUA (-9050 5575);
FORCEPROP 1 LASTPIN (-8950 5575) $PN 1
J 0
(-8938 5587);
DISPLAY 0.617021 (-8938 5587);
PAINT MONO (-8938 5587);
FORCEPROP 1 LASTPIN (-8750 5575) $PN 2
J 0
(-8788 5587);
DISPLAY 0.617021 (-8788 5587);
PAINT MONO (-8788 5587);
FORCEPROP 2 LAST CDS_LIB pure_quanta
J 0
(-8850 5575);
DISPLAY INVISIBLE (-8850 5575);
FORCEPROP 1 LAST PATH I49
J 0
(-8900 5725);
DISPLAY 0.978723 (-8900 5725);
PAINT WHITE (-8900 5725);
DISPLAY INVISIBLE (-8900 5725);
FORCEPROP 1 LAST LOCATION PR120
J 0
(-8900 5675);
DISPLAY 1.021277 (-8900 5675);
PAINT AQUA (-8900 5675);
DISPLAY INVISIBLE (-8900 5675);
FORCEPROP 0 LAST $SEC 1
J 0
(-8900 5675);
DISPLAY 0.680851 (-8900 5675);
PAINT MONO (-8900 5675);
DISPLAY INVISIBLE (-8900 5675);
FORCEPROP 0 LAST CDS_SEC 1
J 0
(-8900 5675);
DISPLAY 1.021277 (-8900 5675);
DISPLAY INVISIBLE (-8900 5675);
FORCEADD UNIVERSAL_GND..1
(-9750 2025);
FORCEPROP 3 LASTPIN (-9750 2075) SIG_NAME GND\g
J 0
(-9740 2085);
DISPLAY 0.659574 (-9740 2085);
PAINT MONO (-9740 2085);
DISPLAY INVISIBLE (-9740 2085);
FORCEPROP 1 LAST HDL_POWER GND
J 1
(-9725 1950);
DISPLAY 0.872340 (-9725 1950);
PAINT GREEN (-9725 1950);
DISPLAY INVISIBLE (-9725 1950);
FORCEPROP 2 LAST CDS_LIB logical_power
J 0
(-9750 2025);
PAINT MONO (-9750 2025);
DISPLAY INVISIBLE (-9750 2025);
FORCEPROP 1 LAST PATH I5
J 0
(-9675 2025);
DISPLAY 0.872340 (-9675 2025);
PAINT AQUA (-9675 2025);
DISPLAY INVISIBLE (-9675 2025);
FORCEADD Q_CAP..1
(-8400 5400);
FORCEPROP 1 LAST PART_NUMBER TMP_QCH2336K1B12
J 0
(-8350 5225);
DISPLAY 0.617021 (-8350 5225);
PAINT BLUE (-8350 5225);
DISPLAY INVISIBLE (-8350 5225);
FORCEPROP 1 LAST VALUE 3300PF
J 0
(-8350 5475);
DISPLAY 0.617021 (-8350 5475);
PAINT SKYBLUE (-8350 5475);
FORCEPROP 1 LAST PACK_TYPE 0402
J 0
(-8350 5275);
DISPLAY 0.617021 (-8350 5275);
PAINT SKYBLUE (-8350 5275);
FORCEPROP 1 LAST MATERIAL X7R
J 0
(-8350 5325);
DISPLAY 0.617021 (-8350 5325);
PAINT SKYBLUE (-8350 5325);
FORCEPROP 1 LAST TOLERANCE 10%
J 0
(-8350 5375);
DISPLAY 0.617021 (-8350 5375);
PAINT SKYBLUE (-8350 5375);
FORCEPROP 1 LAST VOLTAGE 50V
J 0
(-8350 5425);
DISPLAY 0.617021 (-8350 5425);
PAINT SKYBLUE (-8350 5425);
FORCEPROP 1 LAST LOCATION PC215
J 0
(-8350 5525);
DISPLAY 0.617021 (-8350 5525);
PAINT AQUA (-8350 5525);
FORCEPROP 1 LASTPIN (-8400 5500) $PN 1
J 0
(-8390 5480);
DISPLAY 0.617021 (-8390 5480);
PAINT MONO (-8390 5480);
FORCEPROP 1 LASTPIN (-8400 5300) $PN 2
J 0
(-8390 5280);
DISPLAY 0.617021 (-8390 5280);
PAINT MONO (-8390 5280);
FORCEPROP 2 LAST CDS_LIB pure_quanta
J 0
(-8400 5400);
DISPLAY INVISIBLE (-8400 5400);
FORCEPROP 1 LAST PATH I50
J 0
(-8350 5550);
DISPLAY 0.978723 (-8350 5550);
PAINT WHITE (-8350 5550);
DISPLAY INVISIBLE (-8350 5550);
FORCEPROP 1 LAST LOCATION PC215
J 0
(-8350 5525);
DISPLAY 1.021277 (-8350 5525);
PAINT AQUA (-8350 5525);
DISPLAY INVISIBLE (-8350 5525);
FORCEPROP 0 LAST $SEC 1
J 0
(-8350 5525);
DISPLAY 0.680851 (-8350 5525);
PAINT MONO (-8350 5525);
DISPLAY INVISIBLE (-8350 5525);
FORCEPROP 0 LAST CDS_SEC 1
J 0
(-8350 5525);
DISPLAY 1.021277 (-8350 5525);
DISPLAY INVISIBLE (-8350 5525);
FORCEADD Q_RES..1
(-9200 6275);
FORCEPROP 1 LAST PART_NUMBER CS00002JB13
J 0
(-9075 6325);
DISPLAY 0.617021 (-9075 6325);
PAINT BLUE (-9075 6325);
DISPLAY INVISIBLE (-9075 6325);
FORCEPROP 1 LAST MATERIAL CHIP
J 0
(-9075 6375);
DISPLAY 0.617021 (-9075 6375);
PAINT SKYBLUE (-9075 6375);
FORCEPROP 1 LAST VALUE 0
J 2
(-9050 6275);
DISPLAY 0.617021 (-9050 6275);
PAINT SKYBLUE (-9050 6275);
FORCEPROP 1 LAST TOLERANCE 5%
J 0
(-9025 6275);
DISPLAY 0.617021 (-9025 6275);
PAINT SKYBLUE (-9025 6275);
FORCEPROP 1 LAST WATTAGE 1/16W
J 2
(-8775 6375);
DISPLAY 0.617021 (-8775 6375);
PAINT SKYBLUE (-8775 6375);
FORCEPROP 1 LAST PACK_TYPE 0402LF
J 0
(-8950 6275);
DISPLAY 0.617021 (-8950 6275);
PAINT SKYBLUE (-8950 6275);
FORCEPROP 1 LAST LOCATION R2391
J 0
(-9425 6275);
DISPLAY 0.617021 (-9425 6275);
PAINT AQUA (-9425 6275);
FORCEPROP 1 LASTPIN (-9300 6275) $PN 1
J 0
(-9288 6287);
DISPLAY 0.617021 (-9288 6287);
PAINT MONO (-9288 6287);
FORCEPROP 1 LASTPIN (-9100 6275) $PN 2
J 0
(-9138 6287);
DISPLAY 0.617021 (-9138 6287);
PAINT MONO (-9138 6287);
FORCEPROP 2 LAST CDS_LIB pure_quanta
J 0
(-9200 6275);
DISPLAY INVISIBLE (-9200 6275);
FORCEPROP 1 LAST PATH I51
J 0
(-9250 6425);
DISPLAY 0.978723 (-9250 6425);
PAINT WHITE (-9250 6425);
DISPLAY INVISIBLE (-9250 6425);
FORCEPROP 1 LAST LOCATION R2391
J 0
(-9250 6375);
DISPLAY 1.021277 (-9250 6375);
PAINT AQUA (-9250 6375);
DISPLAY INVISIBLE (-9250 6375);
FORCEPROP 0 LAST $SEC 1
J 0
(-9250 6375);
DISPLAY 0.680851 (-9250 6375);
PAINT MONO (-9250 6375);
DISPLAY INVISIBLE (-9250 6375);
FORCEPROP 0 LAST CDS_SEC 1
J 0
(-9250 6375);
DISPLAY 1.021277 (-9250 6375);
DISPLAY INVISIBLE (-9250 6375);
FORCEADD Q_RES..1
(-9200 6825);
FORCEPROP 1 LAST PART_NUMBER CS00002JB13
J 0
(-9075 6875);
DISPLAY 0.617021 (-9075 6875);
PAINT BLUE (-9075 6875);
DISPLAY INVISIBLE (-9075 6875);
FORCEPROP 1 LAST MATERIAL CHIP
J 0
(-9075 6925);
DISPLAY 0.617021 (-9075 6925);
PAINT SKYBLUE (-9075 6925);
FORCEPROP 1 LAST TOLERANCE 5%
J 0
(-9025 6825);
DISPLAY 0.617021 (-9025 6825);
PAINT SKYBLUE (-9025 6825);
FORCEPROP 1 LAST PACK_TYPE 0402LF
J 0
(-8950 6825);
DISPLAY 0.617021 (-8950 6825);
PAINT SKYBLUE (-8950 6825);
FORCEPROP 1 LAST WATTAGE 1/16W
J 2
(-8775 6925);
DISPLAY 0.617021 (-8775 6925);
PAINT SKYBLUE (-8775 6925);
FORCEPROP 1 LAST VALUE 0
J 2
(-9050 6825);
DISPLAY 0.617021 (-9050 6825);
PAINT SKYBLUE (-9050 6825);
FORCEPROP 1 LAST LOCATION R2389
J 0
(-9425 6825);
DISPLAY 0.617021 (-9425 6825);
PAINT AQUA (-9425 6825);
FORCEPROP 1 LASTPIN (-9300 6825) $PN 1
J 0
(-9288 6837);
DISPLAY 0.617021 (-9288 6837);
PAINT MONO (-9288 6837);
FORCEPROP 1 LASTPIN (-9100 6825) $PN 2
J 0
(-9138 6837);
DISPLAY 0.617021 (-9138 6837);
PAINT MONO (-9138 6837);
FORCEPROP 2 LAST CDS_LIB pure_quanta
J 0
(-9200 6825);
DISPLAY INVISIBLE (-9200 6825);
FORCEPROP 1 LAST PATH I52
J 0
(-9250 6975);
DISPLAY 0.978723 (-9250 6975);
PAINT WHITE (-9250 6975);
DISPLAY INVISIBLE (-9250 6975);
FORCEPROP 1 LAST LOCATION R2389
J 0
(-9250 6925);
DISPLAY 1.021277 (-9250 6925);
PAINT AQUA (-9250 6925);
DISPLAY INVISIBLE (-9250 6925);
FORCEPROP 0 LAST $SEC 1
J 0
(-9250 6925);
DISPLAY 0.680851 (-9250 6925);
PAINT MONO (-9250 6925);
DISPLAY INVISIBLE (-9250 6925);
FORCEPROP 0 LAST CDS_SEC 1
J 0
(-9250 6925);
DISPLAY 1.021277 (-9250 6925);
DISPLAY INVISIBLE (-9250 6925);
FORCEADD Q_RES..1
(-9200 6425);
FORCEPROP 1 LAST PART_NUMBER CS00002JB13
J 0
(-9300 6475);
DISPLAY 0.319149 (-9300 6475);
DISPLAY INVISIBLE (-9300 6475);
FORCEPROP 1 LAST PACK_TYPE 0402LF
J 0
(-9300 6500);
DISPLAY 0.319149 (-9300 6500);
FORCEPROP 1 LAST MATERIAL CHIP
J 0
(-8925 6425);
DISPLAY 0.638298 (-8925 6425);
FORCEPROP 1 LAST TOLERANCE 5%
J 0
(-9000 6425);
DISPLAY 0.638298 (-9000 6425);
FORCEPROP 1 LAST VALUE 0
J 2
(-9025 6425);
DISPLAY 0.638298 (-9025 6425);
FORCEPROP 1 LAST WATTAGE 1/16W
J 2
(-9125 6500);
DISPLAY 0.319149 (-9125 6500);
FORCEPROP 1 LAST LOCATION R2390
J 0
(-9525 6425);
DISPLAY 0.638298 (-9525 6425);
FORCEPROP 1 LASTPIN (-9300 6425) $PN 1
J 0
(-9288 6437);
DISPLAY 0.787234 (-9288 6437);
PAINT MONO (-9288 6437);
FORCEPROP 1 LASTPIN (-9100 6425) $PN 2
J 0
(-9138 6437);
DISPLAY 0.787234 (-9138 6437);
PAINT MONO (-9138 6437);
FORCEPROP 2 LAST SEC_TYPE 0402LF
J 0
(-9250 6625);
DISPLAY 1.021277 (-9250 6625);
DISPLAY INVISIBLE (-9250 6625);
FORCEPROP 2 LAST CDS_LIB pure_quanta
J 0
(-9200 6425);
DISPLAY INVISIBLE (-9200 6425);
FORCEPROP 1 LAST PATH I53
J 0
(-9250 6575);
DISPLAY 0.978723 (-9250 6575);
PAINT WHITE (-9250 6575);
DISPLAY INVISIBLE (-9250 6575);
FORCEPROP 2 LAST SEC 1
J 0
(-9250 6625);
DISPLAY 0.680851 (-9250 6625);
PAINT MONO (-9250 6625);
DISPLAY INVISIBLE (-9250 6625);
FORCEADD VCC15..1
(-9625 7825);
FORCEPROP 3 LASTPIN (-9625 7775) SIG_NAME P3V3_AUX\g
J 0
(-9615 7785);
DISPLAY 0.659574 (-9615 7785);
PAINT MONO (-9615 7785);
DISPLAY INVISIBLE (-9615 7785);
FORCEPROP 1 LAST HDL_POWER P3V3_AUX
J 1
(-9625 7875);
DISPLAY 0.617021 (-9625 7875);
PAINT GREEN (-9625 7875);
FORCEPROP 2 LAST CDS_LIB logical_power
J 0
(-9625 7825);
PAINT MONO (-9625 7825);
DISPLAY INVISIBLE (-9625 7825);
FORCEPROP 1 LAST PATH I54
J 0
(-9575 7850);
DISPLAY 0.872340 (-9575 7850);
PAINT AQUA (-9575 7850);
DISPLAY INVISIBLE (-9575 7850);
FORCEADD Q_RES..1
(-9200 7425);
FORCEPROP 1 LAST PART_NUMBER CS00002JB13
J 0
(-9075 7475);
DISPLAY 0.617021 (-9075 7475);
PAINT BLUE (-9075 7475);
DISPLAY INVISIBLE (-9075 7475);
FORCEPROP 1 LAST TOLERANCE 5%
J 0
(-9025 7425);
DISPLAY 0.617021 (-9025 7425);
PAINT SKYBLUE (-9025 7425);
FORCEPROP 1 LAST VALUE 0
J 2
(-9050 7425);
DISPLAY 0.617021 (-9050 7425);
PAINT SKYBLUE (-9050 7425);
FORCEPROP 1 LAST PACK_TYPE 0402LF
J 0
(-8950 7425);
DISPLAY 0.617021 (-8950 7425);
PAINT SKYBLUE (-8950 7425);
FORCEPROP 1 LAST MATERIAL CHIP
J 0
(-9075 7525);
DISPLAY 0.617021 (-9075 7525);
PAINT SKYBLUE (-9075 7525);
FORCEPROP 1 LAST WATTAGE 1/16W
J 2
(-8775 7525);
DISPLAY 0.617021 (-8775 7525);
PAINT SKYBLUE (-8775 7525);
FORCEPROP 1 LAST LOCATION R2594
J 0
(-9425 7425);
DISPLAY 0.617021 (-9425 7425);
PAINT AQUA (-9425 7425);
FORCEPROP 1 LASTPIN (-9300 7425) $PN 1
J 0
(-9288 7437);
DISPLAY 0.617021 (-9288 7437);
PAINT MONO (-9288 7437);
FORCEPROP 1 LASTPIN (-9100 7425) $PN 2
J 0
(-9138 7437);
DISPLAY 0.617021 (-9138 7437);
PAINT MONO (-9138 7437);
FORCEPROP 2 LAST CDS_LIB pure_quanta
J 0
(-9200 7425);
DISPLAY INVISIBLE (-9200 7425);
FORCEPROP 1 LAST PATH I55
J 0
(-9250 7575);
DISPLAY 0.978723 (-9250 7575);
PAINT WHITE (-9250 7575);
DISPLAY INVISIBLE (-9250 7575);
FORCEPROP 1 LAST LOCATION R2594
J 0
(-9250 7525);
DISPLAY 1.021277 (-9250 7525);
PAINT AQUA (-9250 7525);
DISPLAY INVISIBLE (-9250 7525);
FORCEPROP 0 LAST $SEC 1
J 0
(-9250 7525);
DISPLAY 0.680851 (-9250 7525);
PAINT MONO (-9250 7525);
DISPLAY INVISIBLE (-9250 7525);
FORCEPROP 0 LAST CDS_SEC 1
J 0
(-9250 7525);
DISPLAY 1.021277 (-9250 7525);
DISPLAY INVISIBLE (-9250 7525);
FORCEADD Q_RES..1
(-9200 7125);
FORCEPROP 1 LAST PART_NUMBER CS11502FB07
J 0
(-9075 7175);
DISPLAY 0.617021 (-9075 7175);
PAINT BLUE (-9075 7175);
DISPLAY INVISIBLE (-9075 7175);
FORCEPROP 1 LAST MATERIAL CHIP
J 0
(-9075 7225);
DISPLAY 0.617021 (-9075 7225);
PAINT SKYBLUE (-9075 7225);
FORCEPROP 1 LAST WATTAGE 1/16W
J 2
(-8775 7225);
DISPLAY 0.617021 (-8775 7225);
PAINT SKYBLUE (-8775 7225);
FORCEPROP 1 LAST VALUE 150
J 2
(-8975 7125);
DISPLAY 0.617021 (-8975 7125);
PAINT SKYBLUE (-8975 7125);
FORCEPROP 1 LAST TOLERANCE 1%
J 0
(-8950 7125);
DISPLAY 0.617021 (-8950 7125);
PAINT SKYBLUE (-8950 7125);
FORCEPROP 1 LAST PACK_TYPE 0402LF
J 0
(-8850 7125);
DISPLAY 0.617021 (-8850 7125);
PAINT SKYBLUE (-8850 7125);
FORCEPROP 1 LAST LOCATION R2596
J 0
(-9425 7125);
DISPLAY 0.617021 (-9425 7125);
PAINT AQUA (-9425 7125);
FORCEPROP 1 LASTPIN (-9300 7125) $PN 1
J 0
(-9288 7137);
DISPLAY 0.617021 (-9288 7137);
PAINT MONO (-9288 7137);
FORCEPROP 1 LASTPIN (-9100 7125) $PN 2
J 0
(-9138 7137);
DISPLAY 0.617021 (-9138 7137);
PAINT MONO (-9138 7137);
FORCEPROP 2 LAST CDS_LIB pure_quanta
J 0
(-9200 7125);
DISPLAY INVISIBLE (-9200 7125);
FORCEPROP 1 LAST PATH I56
J 0
(-9250 7275);
DISPLAY 0.978723 (-9250 7275);
PAINT WHITE (-9250 7275);
DISPLAY INVISIBLE (-9250 7275);
FORCEPROP 1 LAST LOCATION R2596
J 0
(-9050 7200);
DISPLAY 1.021277 (-9050 7200);
PAINT AQUA (-9050 7200);
DISPLAY INVISIBLE (-9050 7200);
FORCEPROP 0 LAST $SEC 1
J 0
(-9050 7200);
DISPLAY 0.680851 (-9050 7200);
PAINT MONO (-9050 7200);
DISPLAY INVISIBLE (-9050 7200);
FORCEPROP 0 LAST CDS_SEC 1
J 0
(-9050 7200);
DISPLAY 1.021277 (-9050 7200);
DISPLAY INVISIBLE (-9050 7200);
FORCEADD Q_RES..1
(-9200 6975);
FORCEPROP 1 LAST PART_NUMBER CS00002JB13
J 0
(-9075 7025);
DISPLAY 0.617021 (-9075 7025);
PAINT BLUE (-9075 7025);
DISPLAY INVISIBLE (-9075 7025);
FORCEPROP 1 LAST PACK_TYPE 0402LF
J 0
(-8950 6975);
DISPLAY 0.617021 (-8950 6975);
PAINT SKYBLUE (-8950 6975);
FORCEPROP 1 LAST TOLERANCE 5%
J 0
(-9025 6975);
DISPLAY 0.617021 (-9025 6975);
PAINT SKYBLUE (-9025 6975);
FORCEPROP 1 LAST VALUE 0
J 2
(-9050 6975);
DISPLAY 0.617021 (-9050 6975);
PAINT SKYBLUE (-9050 6975);
FORCEPROP 1 LAST MATERIAL CHIP
J 0
(-9075 7075);
DISPLAY 0.617021 (-9075 7075);
PAINT SKYBLUE (-9075 7075);
FORCEPROP 1 LAST WATTAGE 1/16W
J 2
(-8775 7075);
DISPLAY 0.617021 (-8775 7075);
PAINT SKYBLUE (-8775 7075);
FORCEPROP 1 LAST LOCATION R2388
J 0
(-9425 6975);
DISPLAY 0.617021 (-9425 6975);
PAINT AQUA (-9425 6975);
FORCEPROP 1 LASTPIN (-9300 6975) $PN 1
J 0
(-9288 6987);
DISPLAY 0.617021 (-9288 6987);
PAINT MONO (-9288 6987);
FORCEPROP 1 LASTPIN (-9100 6975) $PN 2
J 0
(-9138 6987);
DISPLAY 0.617021 (-9138 6987);
PAINT MONO (-9138 6987);
FORCEPROP 2 LAST CDS_LIB pure_quanta
J 0
(-9200 6975);
DISPLAY INVISIBLE (-9200 6975);
FORCEPROP 1 LAST PATH I57
J 0
(-9250 7125);
DISPLAY 0.978723 (-9250 7125);
PAINT WHITE (-9250 7125);
DISPLAY INVISIBLE (-9250 7125);
FORCEPROP 1 LAST LOCATION R2388
J 0
(-9250 7075);
DISPLAY 1.021277 (-9250 7075);
PAINT AQUA (-9250 7075);
DISPLAY INVISIBLE (-9250 7075);
FORCEPROP 0 LAST $SEC 1
J 0
(-9250 7075);
DISPLAY 0.680851 (-9250 7075);
PAINT MONO (-9250 7075);
DISPLAY INVISIBLE (-9250 7075);
FORCEPROP 0 LAST CDS_SEC 1
J 0
(-9250 7075);
DISPLAY 1.021277 (-9250 7075);
DISPLAY INVISIBLE (-9250 7075);
FORCEADD Q_RES..1
(-9200 7575);
FORCEPROP 1 LAST PART_NUMBER CS00002JB13
J 0
(-9075 7625);
DISPLAY 0.617021 (-9075 7625);
PAINT BLUE (-9075 7625);
DISPLAY INVISIBLE (-9075 7625);
FORCEPROP 1 LAST WATTAGE 1/16W
J 2
(-8775 7675);
DISPLAY 0.617021 (-8775 7675);
PAINT SKYBLUE (-8775 7675);
FORCEPROP 1 LAST MATERIAL CHIP
J 0
(-9075 7675);
DISPLAY 0.617021 (-9075 7675);
PAINT SKYBLUE (-9075 7675);
FORCEPROP 1 LAST PACK_TYPE 0402LF
J 0
(-8950 7575);
DISPLAY 0.617021 (-8950 7575);
PAINT SKYBLUE (-8950 7575);
FORCEPROP 1 LAST TOLERANCE 5%
J 0
(-9025 7575);
DISPLAY 0.617021 (-9025 7575);
PAINT SKYBLUE (-9025 7575);
FORCEPROP 1 LAST VALUE 0
J 2
(-9050 7575);
DISPLAY 0.617021 (-9050 7575);
PAINT SKYBLUE (-9050 7575);
FORCEPROP 1 LAST LOCATION R2595
J 0
(-9425 7575);
DISPLAY 0.617021 (-9425 7575);
PAINT AQUA (-9425 7575);
FORCEPROP 1 LASTPIN (-9300 7575) $PN 1
J 0
(-9288 7587);
DISPLAY 0.617021 (-9288 7587);
PAINT MONO (-9288 7587);
FORCEPROP 1 LASTPIN (-9100 7575) $PN 2
J 0
(-9138 7587);
DISPLAY 0.617021 (-9138 7587);
PAINT MONO (-9138 7587);
FORCEPROP 2 LAST CDS_LIB pure_quanta
J 0
(-9200 7575);
DISPLAY INVISIBLE (-9200 7575);
FORCEPROP 1 LAST PATH I58
J 0
(-9250 7725);
DISPLAY 0.978723 (-9250 7725);
PAINT WHITE (-9250 7725);
DISPLAY INVISIBLE (-9250 7725);
FORCEPROP 1 LAST LOCATION R2595
J 0
(-9250 7675);
DISPLAY 1.021277 (-9250 7675);
PAINT AQUA (-9250 7675);
DISPLAY INVISIBLE (-9250 7675);
FORCEPROP 0 LAST $SEC 1
J 0
(-9250 7675);
DISPLAY 0.680851 (-9250 7675);
PAINT MONO (-9250 7675);
DISPLAY INVISIBLE (-9250 7675);
FORCEPROP 0 LAST CDS_SEC 1
J 0
(-9250 7675);
DISPLAY 1.021277 (-9250 7675);
DISPLAY INVISIBLE (-9250 7675);
FORCEADD Q_RES..1
(-9200 7725);
FORCEPROP 1 LAST PART_NUMBER CS21002FB06
J 0
(-9075 7775);
DISPLAY 0.617021 (-9075 7775);
PAINT BLUE (-9075 7775);
DISPLAY INVISIBLE (-9075 7775);
FORCEPROP 1 LAST PACK_TYPE 0402LF
J 0
(-8900 7725);
DISPLAY 0.617021 (-8900 7725);
PAINT SKYBLUE (-8900 7725);
FORCEPROP 1 LAST MATERIAL CHIP
J 0
(-9075 7825);
DISPLAY 0.617021 (-9075 7825);
PAINT SKYBLUE (-9075 7825);
FORCEPROP 1 LAST TOLERANCE 1%
J 0
(-9000 7725);
DISPLAY 0.617021 (-9000 7725);
PAINT SKYBLUE (-9000 7725);
FORCEPROP 1 LAST WATTAGE 1/16W
J 2
(-8775 7825);
DISPLAY 0.617021 (-8775 7825);
PAINT SKYBLUE (-8775 7825);
FORCEPROP 1 LAST VALUE 1K
J 2
(-9025 7725);
DISPLAY 0.617021 (-9025 7725);
PAINT SKYBLUE (-9025 7725);
FORCEPROP 1 LAST LOCATION R2383
J 0
(-9425 7725);
DISPLAY 0.617021 (-9425 7725);
PAINT AQUA (-9425 7725);
FORCEPROP 1 LASTPIN (-9300 7725) $PN 1
J 0
(-9288 7737);
DISPLAY 0.617021 (-9288 7737);
PAINT MONO (-9288 7737);
FORCEPROP 1 LASTPIN (-9100 7725) $PN 2
J 0
(-9138 7737);
DISPLAY 0.617021 (-9138 7737);
PAINT MONO (-9138 7737);
FORCEPROP 2 LAST CDS_LIB pure_quanta
J 0
(-9200 7725);
DISPLAY INVISIBLE (-9200 7725);
FORCEPROP 1 LAST PATH I59
J 0
(-9250 7875);
DISPLAY 0.978723 (-9250 7875);
PAINT WHITE (-9250 7875);
DISPLAY INVISIBLE (-9250 7875);
FORCEPROP 1 LAST LOCATION R2383
J 0
(-9250 7825);
DISPLAY 1.021277 (-9250 7825);
PAINT AQUA (-9250 7825);
DISPLAY INVISIBLE (-9250 7825);
FORCEPROP 0 LAST $SEC 1
J 0
(-9250 7825);
DISPLAY 0.680851 (-9250 7825);
PAINT MONO (-9250 7825);
DISPLAY INVISIBLE (-9250 7825);
FORCEPROP 0 LAST CDS_SEC 1
J 0
(-9250 7825);
DISPLAY 1.021277 (-9250 7825);
DISPLAY INVISIBLE (-9250 7825);
FORCEADD Q_CAP..2
(-8375 7300);
FORCEPROP 1 LAST PART_NUMBER TMP_QCH21006JB10
J 1
(-8100 7250);
DISPLAY 0.617021 (-8100 7250);
PAINT BLUE (-8100 7250);
DISPLAY INVISIBLE (-8100 7250);
FORCEPROP 1 LAST MATERIAL X7R
J 0
(-7900 7300);
DISPLAY 0.617021 (-7900 7300);
PAINT SKYBLUE (-7900 7300);
FORCEPROP 1 LAST VALUE 1000PF
J 2
(-8050 7300);
DISPLAY 0.617021 (-8050 7300);
PAINT SKYBLUE (-8050 7300);
FORCEPROP 1 LAST VOLTAGE 50V
J 0
(-8025 7300);
DISPLAY 0.617021 (-8025 7300);
PAINT SKYBLUE (-8025 7300);
FORCEPROP 1 LAST TOLERANCE 5%
J 2
(-7725 7250);
DISPLAY 0.617021 (-7725 7250);
PAINT SKYBLUE (-7725 7250);
FORCEPROP 1 LAST PACK_TYPE 0402
J 1
(-7825 7200);
DISPLAY 0.617021 (-7825 7200);
PAINT SKYBLUE (-7825 7200);
FORCEPROP 1 LAST LOCATION C3274
J 1
(-8575 7300);
DISPLAY 0.617021 (-8575 7300);
PAINT AQUA (-8575 7300);
FORCEPROP 1 LASTPIN (-8475 7300) $PN 1
J 0
(-8485 7315);
DISPLAY 0.617021 (-8485 7315);
PAINT MONO (-8485 7315);
FORCEPROP 1 LASTPIN (-8275 7300) $PN 2
J 0
(-8290 7315);
DISPLAY 0.617021 (-8290 7315);
PAINT MONO (-8290 7315);
FORCEPROP 2 LAST CDS_LIB pure_quanta
J 0
(-8375 7300);
DISPLAY INVISIBLE (-8375 7300);
FORCEPROP 1 LAST PATH I60
J 0
(-8375 7500);
DISPLAY 0.978723 (-8375 7500);
PAINT WHITE (-8375 7500);
DISPLAY INVISIBLE (-8375 7500);
FORCEPROP 1 LAST LOCATION C3274
J 0
(-8425 7400);
DISPLAY 1.021277 (-8425 7400);
PAINT AQUA (-8425 7400);
DISPLAY INVISIBLE (-8425 7400);
FORCEPROP 0 LAST $SEC 1
J 0
(-8425 7400);
DISPLAY 0.680851 (-8425 7400);
PAINT MONO (-8425 7400);
DISPLAY INVISIBLE (-8425 7400);
FORCEPROP 0 LAST CDS_SEC 1
J 0
(-8425 7400);
DISPLAY 1.021277 (-8425 7400);
DISPLAY INVISIBLE (-8425 7400);
FORCEADD Q_CAP..2
(-8350 7725);
FORCEPROP 1 LAST PART_NUMBER TMP_QCH21006JB10
J 1
(-8075 7675);
DISPLAY 0.617021 (-8075 7675);
PAINT BLUE (-8075 7675);
DISPLAY INVISIBLE (-8075 7675);
FORCEPROP 1 LAST MATERIAL EMPTY
J 0
(-7875 7725);
DISPLAY 0.617021 (-7875 7725);
PAINT RED (-7875 7725);
FORCEPROP 1 LAST TOLERANCE 5%
J 2
(-7700 7675);
DISPLAY 0.617021 (-7700 7675);
PAINT SKYBLUE (-7700 7675);
FORCEPROP 1 LAST VALUE 1000PF
J 2
(-8025 7725);
DISPLAY 0.617021 (-8025 7725);
PAINT SKYBLUE (-8025 7725);
FORCEPROP 1 LAST VOLTAGE 50V
J 0
(-8000 7725);
DISPLAY 0.617021 (-8000 7725);
PAINT SKYBLUE (-8000 7725);
FORCEPROP 1 LAST PACK_TYPE 0402
J 1
(-7800 7625);
DISPLAY 0.617021 (-7800 7625);
PAINT SKYBLUE (-7800 7625);
FORCEPROP 1 LAST LOCATION C3273
J 1
(-8550 7725);
DISPLAY 0.617021 (-8550 7725);
PAINT AQUA (-8550 7725);
FORCEPROP 1 LASTPIN (-8450 7725) $PN 1
J 0
(-8460 7740);
DISPLAY 0.617021 (-8460 7740);
PAINT MONO (-8460 7740);
FORCEPROP 1 LASTPIN (-8250 7725) $PN 2
J 0
(-8265 7740);
DISPLAY 0.617021 (-8265 7740);
PAINT MONO (-8265 7740);
FORCEPROP 2 LAST CDS_LIB pure_quanta
J 0
(-8350 7725);
DISPLAY INVISIBLE (-8350 7725);
FORCEPROP 1 LAST PATH I61
J 0
(-8350 7925);
DISPLAY 0.978723 (-8350 7925);
PAINT WHITE (-8350 7925);
DISPLAY INVISIBLE (-8350 7925);
FORCEPROP 1 LAST LOCATION C3273
J 0
(-8400 7825);
DISPLAY 1.021277 (-8400 7825);
PAINT AQUA (-8400 7825);
DISPLAY INVISIBLE (-8400 7825);
FORCEPROP 0 LAST $SEC 1
J 0
(-8400 7825);
DISPLAY 0.680851 (-8400 7825);
PAINT MONO (-8400 7825);
DISPLAY INVISIBLE (-8400 7825);
FORCEPROP 0 LAST CDS_SEC 1
J 0
(-8400 7825);
DISPLAY 1.021277 (-8400 7825);
DISPLAY INVISIBLE (-8400 7825);
FORCEADD UNIVERSAL_GND..1
(-7750 1625);
FORCEPROP 3 LASTPIN (-7750 1675) SIG_NAME GND\g
J 0
(-7740 1685);
DISPLAY 0.659574 (-7740 1685);
PAINT MONO (-7740 1685);
DISPLAY INVISIBLE (-7740 1685);
FORCEPROP 1 LAST HDL_POWER GND
J 1
(-7725 1550);
DISPLAY 0.872340 (-7725 1550);
PAINT GREEN (-7725 1550);
DISPLAY INVISIBLE (-7725 1550);
FORCEPROP 2 LAST CDS_LIB logical_power
J 0
(-7750 1625);
PAINT MONO (-7750 1625);
DISPLAY INVISIBLE (-7750 1625);
FORCEPROP 1 LAST PATH I62
J 0
(-7675 1625);
DISPLAY 0.872340 (-7675 1625);
PAINT AQUA (-7675 1625);
DISPLAY INVISIBLE (-7675 1625);
FORCEADD Q_CAP..1
(-7750 1925);
FORCEPROP 1 LAST PART_NUMBER CH4104K1B00
J 0
(-7700 1750);
DISPLAY 0.617021 (-7700 1750);
PAINT BLUE (-7700 1750);
DISPLAY INVISIBLE (-7700 1750);
FORCEPROP 1 LAST VALUE 0.1UF
J 0
(-7700 2000);
DISPLAY 0.617021 (-7700 2000);
PAINT SKYBLUE (-7700 2000);
FORCEPROP 1 LAST TOLERANCE 10%
J 0
(-7700 1900);
DISPLAY 0.617021 (-7700 1900);
PAINT SKYBLUE (-7700 1900);
FORCEPROP 1 LAST MATERIAL X7R
J 0
(-7700 1850);
DISPLAY 0.617021 (-7700 1850);
PAINT SKYBLUE (-7700 1850);
FORCEPROP 1 LAST PACK_TYPE 0402
J 0
(-7700 1800);
DISPLAY 0.617021 (-7700 1800);
PAINT SKYBLUE (-7700 1800);
FORCEPROP 1 LAST VOLTAGE 25V
J 0
(-7700 1950);
DISPLAY 0.617021 (-7700 1950);
PAINT SKYBLUE (-7700 1950);
FORCEPROP 1 LAST LOCATION PC221
J 0
(-7700 2050);
DISPLAY 0.617021 (-7700 2050);
PAINT AQUA (-7700 2050);
FORCEPROP 1 LASTPIN (-7750 2025) $PN 1
J 0
(-7740 2005);
DISPLAY 0.617021 (-7740 2005);
PAINT MONO (-7740 2005);
FORCEPROP 1 LASTPIN (-7750 1825) $PN 2
J 0
(-7740 1805);
DISPLAY 0.617021 (-7740 1805);
PAINT MONO (-7740 1805);
FORCEPROP 2 LAST CDS_LIB pure_quanta
J 0
(-7750 1925);
DISPLAY INVISIBLE (-7750 1925);
FORCEPROP 1 LAST PATH I63
J 0
(-7700 2075);
DISPLAY 0.978723 (-7700 2075);
PAINT WHITE (-7700 2075);
DISPLAY INVISIBLE (-7700 2075);
FORCEPROP 1 LAST LOCATION PC221
J 0
(-7700 2100);
DISPLAY 1.021277 (-7700 2100);
PAINT AQUA (-7700 2100);
DISPLAY INVISIBLE (-7700 2100);
FORCEPROP 0 LAST $SEC 1
J 0
(-7700 2100);
DISPLAY 0.680851 (-7700 2100);
PAINT MONO (-7700 2100);
DISPLAY INVISIBLE (-7700 2100);
FORCEPROP 0 LAST CDS_SEC 1
J 0
(-7700 2100);
DISPLAY 1.021277 (-7700 2100);
DISPLAY INVISIBLE (-7700 2100);
FORCEADD UNIVERSAL_GND..1
(-7575 1900);
FORCEPROP 3 LASTPIN (-7575 1950) SIG_NAME GND\g
J 0
(-7565 1960);
DISPLAY 0.659574 (-7565 1960);
PAINT MONO (-7565 1960);
DISPLAY INVISIBLE (-7565 1960);
FORCEPROP 1 LAST HDL_POWER GND
J 1
(-7550 1825);
DISPLAY 0.872340 (-7550 1825);
PAINT GREEN (-7550 1825);
DISPLAY INVISIBLE (-7550 1825);
FORCEPROP 2 LAST CDS_LIB logical_power
J 0
(-7575 1900);
PAINT MONO (-7575 1900);
DISPLAY INVISIBLE (-7575 1900);
FORCEPROP 1 LAST PATH I64
J 0
(-7500 1900);
DISPLAY 0.872340 (-7500 1900);
PAINT AQUA (-7500 1900);
DISPLAY INVISIBLE (-7500 1900);
FORCEADD ISL69260IRAZT..1
(-6825 4825);
FORCEPROP 1 LAST PART_NUMBER AL069260000
J 0
(-7370 7770);
DISPLAY 0.617021 (-7370 7770);
PAINT BLUE (-7370 7770);
DISPLAY INVISIBLE (-7370 7770);
FORCEPROP 2 LAST VALUE ISL69260IRAZ-T
J 0
(-6875 7850);
DISPLAY 0.617021 (-6875 7850);
PAINT SKYBLUE (-6875 7850);
FORCEPROP 2 LAST PART_TYPE SMLF
J 0
(-6875 7900);
DISPLAY 0.638298 (-6875 7900);
FORCEPROP 1 LAST MATERIAL IC
J 0
(-7370 7683);
DISPLAY 0.617021 (-7370 7683);
PAINT SKYBLUE (-7370 7683);
FORCEPROP 1 LAST LOCATION PU5
J 0
(-7370 7877);
DISPLAY 0.617021 (-7370 7877);
PAINT AQUA (-7370 7877);
FORCEPROP 0 LASTPIN (-7500 2475) $PN 34
J 2
(-7510 2485);
DISPLAY 0.680851 (-7510 2485);
PAINT MONO (-7510 2485);
FORCEPROP 0 LASTPIN (-7500 3575) $PN 33
J 2
(-7510 3585);
DISPLAY 0.680851 (-7510 3585);
PAINT MONO (-7510 3585);
FORCEPROP 0 LASTPIN (-6150 3325) $PN 30
J 0
(-6140 3335);
DISPLAY 0.680851 (-6140 3335);
PAINT MONO (-6140 3335);
FORCEPROP 0 LASTPIN (-6150 3775) $PN 29
J 0
(-6140 3785);
DISPLAY 0.680851 (-6140 3785);
PAINT MONO (-6140 3785);
FORCEPROP 0 LASTPIN (-6150 4225) $PN 28
J 0
(-6140 4235);
DISPLAY 0.680851 (-6140 4235);
PAINT MONO (-6140 4235);
FORCEPROP 0 LASTPIN (-6150 4675) $PN 27
J 0
(-6140 4685);
DISPLAY 0.680851 (-6140 4685);
PAINT MONO (-6140 4685);
FORCEPROP 0 LASTPIN (-6150 5125) $PN 26
J 0
(-6140 5135);
DISPLAY 0.680851 (-6140 5135);
PAINT MONO (-6140 5135);
FORCEPROP 0 LASTPIN (-6150 5575) $PN 25
J 0
(-6140 5585);
DISPLAY 0.680851 (-6140 5585);
PAINT MONO (-6140 5585);
FORCEPROP 0 LASTPIN (-6150 6025) $PN 24
J 0
(-6140 6035);
DISPLAY 0.680851 (-6140 6035);
PAINT MONO (-6140 6035);
FORCEPROP 0 LASTPIN (-6150 6475) $PN 23
J 0
(-6140 6485);
DISPLAY 0.680851 (-6140 6485);
PAINT MONO (-6140 6485);
FORCEPROP 0 LASTPIN (-7500 7425) $PN 13
J 2
(-7510 7435);
DISPLAY 0.680851 (-7510 7435);
PAINT MONO (-7510 7435);
FORCEPROP 0 LASTPIN (-7500 3175) $PN 20
J 2
(-7510 3185);
DISPLAY 0.680851 (-7510 3185);
PAINT MONO (-7510 3185);
FORCEPROP 0 LASTPIN (-7500 7575) $PN 12
J 2
(-7510 7585);
DISPLAY 0.680851 (-7510 7585);
PAINT MONO (-7510 7585);
FORCEPROP 0 LASTPIN (-7500 2775) $PN 16
J 2
(-7510 2785);
DISPLAY 0.680851 (-7510 2785);
PAINT MONO (-7510 2785);
FORCEPROP 0 LASTPIN (-7500 6425) $PN 10
J 2
(-7510 6435);
DISPLAY 0.680851 (-7510 6435);
PAINT MONO (-7510 6435);
FORCEPROP 0 LASTPIN (-7500 6275) $PN 9
J 2
(-7510 6285);
DISPLAY 0.680851 (-7510 6285);
PAINT MONO (-7510 6285);
FORCEPROP 0 LASTPIN (-6150 3425) $PN 1
J 0
(-6140 3435);
DISPLAY 0.680851 (-6140 3435);
PAINT MONO (-6140 3435);
FORCEPROP 0 LASTPIN (-6150 3875) $PN 2
J 0
(-6140 3885);
DISPLAY 0.680851 (-6140 3885);
PAINT MONO (-6140 3885);
FORCEPROP 0 LASTPIN (-6150 4325) $PN 3
J 0
(-6140 4335);
DISPLAY 0.680851 (-6140 4335);
PAINT MONO (-6140 4335);
FORCEPROP 0 LASTPIN (-6150 4775) $PN 4
J 0
(-6140 4785);
DISPLAY 0.680851 (-6140 4785);
PAINT MONO (-6140 4785);
FORCEPROP 0 LASTPIN (-6150 5225) $PN 5
J 0
(-6140 5235);
DISPLAY 0.680851 (-6140 5235);
PAINT MONO (-6140 5235);
FORCEPROP 0 LASTPIN (-6150 5675) $PN 6
J 0
(-6140 5685);
DISPLAY 0.680851 (-6140 5685);
PAINT MONO (-6140 5685);
FORCEPROP 0 LASTPIN (-6150 6125) $PN 7
J 0
(-6140 6135);
DISPLAY 0.680851 (-6140 6135);
PAINT MONO (-6140 6135);
FORCEPROP 0 LASTPIN (-6150 6575) $PN 8
J 0
(-6140 6585);
DISPLAY 0.680851 (-6140 6585);
PAINT MONO (-6140 6585);
FORCEPROP 0 LASTPIN (-7500 5275) $PN 22
J 2
(-7510 5285);
DISPLAY 0.680851 (-7510 5285);
PAINT MONO (-7510 5285);
FORCEPROP 0 LASTPIN (-7500 4175) $PN 31
J 2
(-7510 4185);
DISPLAY 0.680851 (-7510 4185);
PAINT MONO (-7510 4185);
FORCEPROP 0 LASTPIN (-7500 7125) $PN 17
J 2
(-7510 7135);
DISPLAY 0.680851 (-7510 7135);
PAINT MONO (-7510 7135);
FORCEPROP 0 LASTPIN (-7500 6975) $PN 18
J 2
(-7510 6985);
DISPLAY 0.680851 (-7510 6985);
PAINT MONO (-7510 6985);
FORCEPROP 0 LASTPIN (-6150 2375) $PN 35
J 0
(-6140 2385);
DISPLAY 0.680851 (-6140 2385);
PAINT MONO (-6140 2385);
FORCEPROP 0 LASTPIN (-6150 2675) $PN 36
J 0
(-6140 2685);
DISPLAY 0.680851 (-6140 2685);
PAINT MONO (-6140 2685);
FORCEPROP 0 LASTPIN (-7500 2025) $PN TH
J 2
(-7510 2035);
DISPLAY 0.680851 (-7510 2035);
PAINT MONO (-7510 2035);
FORCEPROP 0 LASTPIN (-6150 7575) $PN 39
J 0
(-6140 7585);
DISPLAY 0.680851 (-6140 7585);
PAINT MONO (-6140 7585);
FORCEPROP 0 LASTPIN (-6150 7275) $PN 40
J 0
(-6140 7285);
DISPLAY 0.680851 (-6140 7285);
PAINT MONO (-6140 7285);
FORCEPROP 0 LASTPIN (-7500 5525) $PN 21
J 2
(-7510 5535);
DISPLAY 0.680851 (-7510 5535);
PAINT MONO (-7510 5535);
FORCEPROP 0 LASTPIN (-7500 4425) $PN 32
J 2
(-7510 4435);
DISPLAY 0.680851 (-7510 4435);
PAINT MONO (-7510 4435);
FORCEPROP 0 LASTPIN (-7500 3325) $PN 15
J 2
(-7510 3335);
DISPLAY 0.680851 (-7510 3335);
PAINT MONO (-7510 3335);
FORCEPROP 0 LASTPIN (-7500 6125) $PN 11
J 2
(-7510 6135);
DISPLAY 0.680851 (-7510 6135);
PAINT MONO (-7510 6135);
FORCEPROP 0 LASTPIN (-7500 6825) $PN 19
J 2
(-7510 6835);
DISPLAY 0.680851 (-7510 6835);
PAINT MONO (-7510 6835);
FORCEPROP 0 LASTPIN (-6150 3075) $PN 14
J 0
(-6140 3085);
DISPLAY 0.680851 (-6140 3085);
PAINT MONO (-6140 3085);
FORCEPROP 0 LASTPIN (-7500 2125) $PN 38
J 2
(-7510 2135);
DISPLAY 0.680851 (-7510 2135);
PAINT MONO (-7510 2135);
FORCEPROP 0 LASTPIN (-7500 2225) $PN 37
J 2
(-7510 2235);
DISPLAY 0.680851 (-7510 2235);
PAINT MONO (-7510 2235);
FORCEPROP 1 LAST PATH I65
J 0
(-6825 4825);
DISPLAY 0.723404 (-6825 4825);
PAINT GREEN (-6825 4825);
DISPLAY INVISIBLE (-6825 4825);
FORCEPROP 2 LAST CDS_LIB pure_quanta
J 0
(-6825 4825);
DISPLAY INVISIBLE (-6825 4825);
FORCEPROP 1 LAST CDS_LMAN_SYM_OUTLINE -550,2850,500,-2850
J 0
(-6825 4825);
DISPLAY 0.468085 (-6825 4825);
PAINT GREEN (-6825 4825);
DISPLAY INVISIBLE (-6825 4825);
FORCEPROP 1 LAST NEEDS_NO_SIZE TRUE
J 0
(-6825 4825);
DISPLAY 0.723404 (-6825 4825);
PAINT GREEN (-6825 4825);
DISPLAY INVISIBLE (-6825 4825);
FORCEPROP 0 LAST $SEC 1
J 0
(-6875 7950);
DISPLAY 0.680851 (-6875 7950);
PAINT MONO (-6875 7950);
DISPLAY INVISIBLE (-6875 7950);
FORCEPROP 0 LAST CDS_SEC 1
J 0
(-7325 7925);
DISPLAY 1.021277 (-7325 7925);
DISPLAY INVISIBLE (-7325 7925);
FORCEADD UNIVERSAL_GND..1
R 1
(-7525 2925);
FORCEPROP 3 LASTPIN (-7575 2925) SIG_NAME GND\g
J 0
(-7565 2935);
DISPLAY 0.659574 (-7565 2935);
PAINT MONO (-7565 2935);
DISPLAY INVISIBLE (-7565 2935);
FORCEPROP 1 LAST HDL_POWER GND
R 1
J 1
(-7450 2950);
DISPLAY 0.872340 (-7450 2950);
PAINT GREEN (-7450 2950);
DISPLAY INVISIBLE (-7450 2950);
FORCEPROP 2 LAST CDS_LIB logical_power
J 0
(-7525 2925);
PAINT MONO (-7525 2925);
DISPLAY INVISIBLE (-7525 2925);
FORCEPROP 1 LAST PATH I66
R 1
J 0
(-7525 3000);
DISPLAY 0.872340 (-7525 3000);
PAINT AQUA (-7525 3000);
DISPLAY INVISIBLE (-7525 3000);
FORCEADD UNIVERSAL_GND..1
R 1
(-7525 3050);
FORCEPROP 3 LASTPIN (-7575 3050) SIG_NAME GND\g
J 0
(-7565 3060);
DISPLAY 0.659574 (-7565 3060);
PAINT MONO (-7565 3060);
DISPLAY INVISIBLE (-7565 3060);
FORCEPROP 1 LAST HDL_POWER GND
R 1
J 1
(-7450 3075);
DISPLAY 0.872340 (-7450 3075);
PAINT GREEN (-7450 3075);
DISPLAY INVISIBLE (-7450 3075);
FORCEPROP 2 LAST CDS_LIB logical_power
J 0
(-7525 3050);
PAINT MONO (-7525 3050);
DISPLAY INVISIBLE (-7525 3050);
FORCEPROP 1 LAST PATH I67
R 1
J 0
(-7525 3125);
DISPLAY 0.872340 (-7525 3125);
PAINT AQUA (-7525 3125);
DISPLAY INVISIBLE (-7525 3125);
FORCEADD UNIVERSAL_GND..1
(-6000 1975);
FORCEPROP 3 LASTPIN (-6000 2025) SIG_NAME GND\g
J 0
(-5990 2035);
DISPLAY 0.659574 (-5990 2035);
PAINT MONO (-5990 2035);
DISPLAY INVISIBLE (-5990 2035);
FORCEPROP 1 LAST HDL_POWER GND
J 1
(-5975 1900);
DISPLAY 0.872340 (-5975 1900);
PAINT GREEN (-5975 1900);
DISPLAY INVISIBLE (-5975 1900);
FORCEPROP 2 LAST CDS_LIB logical_power
J 0
(-6000 1975);
PAINT MONO (-6000 1975);
DISPLAY INVISIBLE (-6000 1975);
FORCEPROP 1 LAST PATH I68
J 0
(-5925 1975);
DISPLAY 0.872340 (-5925 1975);
PAINT AQUA (-5925 1975);
DISPLAY INVISIBLE (-5925 1975);
FORCEADD Q_CAP..1
(-6000 2200);
FORCEPROP 1 LAST PART_NUMBER TMP_QCH14706KB18
J 0
(-5950 2000);
DISPLAY 0.617021 (-5950 2000);
PAINT BLUE (-5950 2000);
DISPLAY INVISIBLE (-5950 2000);
FORCEPROP 1 LAST TOLERANCE 10%
J 0
(-5950 2150);
DISPLAY 0.617021 (-5950 2150);
PAINT SKYBLUE (-5950 2150);
FORCEPROP 1 LAST MATERIAL X7R
J 0
(-5950 2100);
DISPLAY 0.617021 (-5950 2100);
PAINT SKYBLUE (-5950 2100);
FORCEPROP 1 LAST VALUE 470PF
J 0
(-5950 2250);
DISPLAY 0.617021 (-5950 2250);
PAINT SKYBLUE (-5950 2250);
FORCEPROP 1 LAST VOLTAGE 50V
J 0
(-5950 2200);
DISPLAY 0.617021 (-5950 2200);
PAINT SKYBLUE (-5950 2200);
FORCEPROP 1 LAST PACK_TYPE 0402
J 0
(-5950 2050);
DISPLAY 0.617021 (-5950 2050);
PAINT SKYBLUE (-5950 2050);
FORCEPROP 1 LAST LOCATION PC222
J 0
(-5950 2300);
DISPLAY 0.617021 (-5950 2300);
PAINT AQUA (-5950 2300);
FORCEPROP 1 LASTPIN (-6000 2300) $PN 1
J 0
(-5990 2280);
DISPLAY 0.617021 (-5990 2280);
PAINT MONO (-5990 2280);
FORCEPROP 1 LASTPIN (-6000 2100) $PN 2
J 0
(-5990 2080);
DISPLAY 0.617021 (-5990 2080);
PAINT MONO (-5990 2080);
FORCEPROP 2 LAST CDS_LIB pure_quanta
J 0
(-6000 2200);
DISPLAY INVISIBLE (-6000 2200);
FORCEPROP 1 LAST PATH I69
J 0
(-5950 2350);
DISPLAY 0.978723 (-5950 2350);
PAINT WHITE (-5950 2350);
DISPLAY INVISIBLE (-5950 2350);
FORCEPROP 1 LAST LOCATION PC222
J 0
(-5950 2350);
DISPLAY 1.021277 (-5950 2350);
PAINT AQUA (-5950 2350);
DISPLAY INVISIBLE (-5950 2350);
FORCEPROP 0 LAST $SEC 1
J 0
(-5950 2350);
DISPLAY 0.680851 (-5950 2350);
PAINT MONO (-5950 2350);
DISPLAY INVISIBLE (-5950 2350);
FORCEPROP 0 LAST CDS_SEC 1
J 0
(-5950 2350);
DISPLAY 1.021277 (-5950 2350);
DISPLAY INVISIBLE (-5950 2350);
FORCEADD Q_RES..1
(-9875 2475);
FORCEPROP 1 LAST PART_NUMBER CS32802FB05
J 0
(-9975 2550);
DISPLAY 0.617021 (-9975 2550);
PAINT BLUE (-9975 2550);
DISPLAY INVISIBLE (-9975 2550);
FORCEPROP 1 LAST PACK_TYPE 0402LF
J 0
(-9550 2475);
DISPLAY 0.617021 (-9550 2475);
PAINT SKYBLUE (-9550 2475);
FORCEPROP 1 LAST VALUE 28K
J 2
(-9650 2475);
DISPLAY 0.617021 (-9650 2475);
PAINT SKYBLUE (-9650 2475);
FORCEPROP 1 LAST TOLERANCE 1%
J 0
(-9625 2475);
DISPLAY 0.617021 (-9625 2475);
PAINT SKYBLUE (-9625 2475);
FORCEPROP 1 LAST MATERIAL EMPTY
J 0
(-9975 2600);
DISPLAY 0.617021 (-9975 2600);
PAINT RED (-9975 2600);
FORCEPROP 1 LAST WATTAGE 1/16W
J 2
(-9650 2600);
DISPLAY 0.617021 (-9650 2600);
PAINT SKYBLUE (-9650 2600);
FORCEPROP 1 LAST LOCATION PR105
J 0
(-10100 2475);
DISPLAY 0.617021 (-10100 2475);
PAINT AQUA (-10100 2475);
FORCEPROP 1 LASTPIN (-9975 2475) $PN 1
J 0
(-9963 2487);
DISPLAY 0.617021 (-9963 2487);
PAINT MONO (-9963 2487);
FORCEPROP 1 LASTPIN (-9775 2475) $PN 2
J 0
(-9813 2487);
DISPLAY 0.617021 (-9813 2487);
PAINT MONO (-9813 2487);
FORCEPROP 2 LAST CDS_LIB pure_quanta
J 0
(-9875 2475);
DISPLAY INVISIBLE (-9875 2475);
FORCEPROP 1 LAST PATH I7
J 0
(-9925 2625);
DISPLAY 0.978723 (-9925 2625);
PAINT WHITE (-9925 2625);
DISPLAY INVISIBLE (-9925 2625);
FORCEPROP 1 LAST LOCATION PR105
J 0
(-9950 2600);
DISPLAY 1.021277 (-9950 2600);
PAINT AQUA (-9950 2600);
DISPLAY INVISIBLE (-9950 2600);
FORCEPROP 0 LAST $SEC 1
J 0
(-9950 2600);
DISPLAY 0.680851 (-9950 2600);
PAINT MONO (-9950 2600);
DISPLAY INVISIBLE (-9950 2600);
FORCEPROP 0 LAST CDS_SEC 1
J 0
(-9950 2600);
DISPLAY 1.021277 (-9950 2600);
DISPLAY INVISIBLE (-9950 2600);
FORCEADD UNIVERSAL_GND..1
(-5250 1925);
FORCEPROP 3 LASTPIN (-5250 1975) SIG_NAME GND\g
J 0
(-5240 1985);
DISPLAY 0.659574 (-5240 1985);
PAINT MONO (-5240 1985);
DISPLAY INVISIBLE (-5240 1985);
FORCEPROP 1 LAST HDL_POWER GND
J 1
(-5225 1850);
DISPLAY 0.872340 (-5225 1850);
PAINT GREEN (-5225 1850);
DISPLAY INVISIBLE (-5225 1850);
FORCEPROP 2 LAST CDS_LIB logical_power
J 0
(-5250 1925);
DISPLAY INVISIBLE (-5250 1925);
FORCEPROP 1 LAST PATH I70
J 0
(-5175 1925);
DISPLAY 0.872340 (-5175 1925);
PAINT AQUA (-5175 1925);
DISPLAY INVISIBLE (-5175 1925);
FORCEADD Q_RES..2
(-5250 2175);
FORCEPROP 1 LAST PART_NUMBER CS31002FB08
J 0
(-5210 2050);
DISPLAY 0.617021 (-5210 2050);
PAINT BLUE (-5210 2050);
DISPLAY INVISIBLE (-5210 2050);
FORCEPROP 1 LAST WATTAGE 1/16W
J 0
(-5210 2150);
DISPLAY 0.617021 (-5210 2150);
PAINT SKYBLUE (-5210 2150);
FORCEPROP 1 LAST MATERIAL EMPTY
J 0
(-5210 2100);
DISPLAY 0.617021 (-5210 2100);
PAINT RED (-5210 2100);
FORCEPROP 1 LAST TOLERANCE 1%
J 0
(-5205 2200);
DISPLAY 0.617021 (-5205 2200);
PAINT SKYBLUE (-5205 2200);
FORCEPROP 1 LAST VALUE 10K
J 0
(-5205 2250);
DISPLAY 0.617021 (-5205 2250);
PAINT SKYBLUE (-5205 2250);
FORCEPROP 1 LAST PACK_TYPE 0402LF
J 0
(-5210 2000);
DISPLAY 0.617021 (-5210 2000);
PAINT SKYBLUE (-5210 2000);
FORCEPROP 1 LAST LOCATION PR435
J 0
(-5205 2300);
DISPLAY 0.617021 (-5205 2300);
PAINT AQUA (-5205 2300);
FORCEPROP 2 LAST CDS_LIB pure_quanta
J 0
(-5250 2175);
DISPLAY INVISIBLE (-5250 2175);
FORCEPROP 1 LAST PATH I71
J 0
(-5200 2350);
DISPLAY 0.978723 (-5200 2350);
PAINT WHITE (-5200 2350);
DISPLAY INVISIBLE (-5200 2350);
FORCEPROP 0 LAST $SEC 1
J 0
(-5200 2350);
DISPLAY INVISIBLE (-5200 2350);
FORCEPROP 0 LAST CDS_SEC 1
J 0
(-5200 2350);
DISPLAY INVISIBLE (-5200 2350);
FORCEPROP 1 LASTPIN (-5250 2275) $PN 1
J 0
(-5245 2237);
DISPLAY 0.787234 (-5245 2237);
PAINT MONO (-5245 2237);
DISPLAY INVISIBLE (-5245 2237);
FORCEPROP 1 LASTPIN (-5250 2075) $PN 2
J 0
(-5245 2085);
DISPLAY 0.787234 (-5245 2085);
PAINT MONO (-5245 2085);
DISPLAY INVISIBLE (-5245 2085);
FORCEADD UNIVERSAL_GND..1
R 1
(-4950 2825);
FORCEPROP 3 LASTPIN (-5000 2825) SIG_NAME GND\g
J 0
(-4990 2835);
DISPLAY 0.659574 (-4990 2835);
PAINT MONO (-4990 2835);
DISPLAY INVISIBLE (-4990 2835);
FORCEPROP 1 LAST HDL_POWER GND
R 1
J 1
(-4875 2850);
DISPLAY 0.872340 (-4875 2850);
PAINT GREEN (-4875 2850);
DISPLAY INVISIBLE (-4875 2850);
FORCEPROP 2 LAST CDS_LIB logical_power
J 0
(-4950 2825);
PAINT MONO (-4950 2825);
DISPLAY INVISIBLE (-4950 2825);
FORCEPROP 1 LAST PATH I72
R 1
J 0
(-4950 2900);
DISPLAY 0.872340 (-4950 2900);
PAINT AQUA (-4950 2900);
DISPLAY INVISIBLE (-4950 2900);
FORCEADD Q_CAP..2
(-5675 2825);
FORCEPROP 1 LAST PART_NUMBER TMP_QCH14706KB18
J 1
(-5350 2875);
DISPLAY 0.617021 (-5350 2875);
PAINT BLUE (-5350 2875);
DISPLAY INVISIBLE (-5350 2875);
FORCEPROP 1 LAST PACK_TYPE 0402
J 1
(-5150 2825);
DISPLAY 0.617021 (-5150 2825);
PAINT SKYBLUE (-5150 2825);
FORCEPROP 1 LAST VOLTAGE 50V
J 0
(-5325 2825);
DISPLAY 0.617021 (-5325 2825);
PAINT SKYBLUE (-5325 2825);
FORCEPROP 1 LAST MATERIAL X7R
J 0
(-5400 2925);
DISPLAY 0.617021 (-5400 2925);
PAINT SKYBLUE (-5400 2925);
FORCEPROP 1 LAST VALUE 470PF
J 2
(-5350 2825);
DISPLAY 0.617021 (-5350 2825);
PAINT SKYBLUE (-5350 2825);
FORCEPROP 1 LAST TOLERANCE 10%
J 2
(-5425 2925);
DISPLAY 0.617021 (-5425 2925);
PAINT SKYBLUE (-5425 2925);
FORCEPROP 1 LAST LOCATION PC1271
J 1
(-5875 2825);
DISPLAY 0.617021 (-5875 2825);
PAINT AQUA (-5875 2825);
FORCEPROP 1 LASTPIN (-5775 2825) $PN 1
J 0
(-5785 2840);
DISPLAY 0.617021 (-5785 2840);
FORCEPROP 1 LASTPIN (-5575 2825) $PN 2
J 0
(-5590 2840);
DISPLAY 0.617021 (-5590 2840);
FORCEPROP 2 LAST CDS_LIB pure_quanta
J 0
(-5675 2825);
PAINT MONO (-5675 2825);
DISPLAY INVISIBLE (-5675 2825);
FORCEPROP 1 LAST PATH I73
J 0
(-5675 3025);
DISPLAY 0.978723 (-5675 3025);
PAINT WHITE (-5675 3025);
DISPLAY INVISIBLE (-5675 3025);
FORCEPROP 2 LAST $SEC 1
J 0
(-5675 3075);
DISPLAY 0.680851 (-5675 3075);
PAINT MONO (-5675 3075);
DISPLAY INVISIBLE (-5675 3075);
FORCEPROP 2 LAST CDS_SEC 1
J 0
(-5675 3075);
DISPLAY 1.021277 (-5675 3075);
DISPLAY INVISIBLE (-5675 3075);
FORCEADD OFFPAGE..4
(-4975 3325);
FORCEPROP 2 LAST $XR0 276 
J 0
(-4789 3325);
DISPLAY 0.638298 (-4789 3325);
PAINT MONO (-4789 3325);
FORCEPROP 1 LAST COMMENT_BODY TRUE
J 0
(-5000 3225);
DISPLAY 0.872340 (-5000 3225);
PAINT GREEN (-5000 3225);
DISPLAY INVISIBLE (-5000 3225);
FORCEPROP 1 LAST OFFPAGE TRUE
J 0
(-4650 3200);
DISPLAY 0.872340 (-4650 3200);
PAINT GREEN (-4650 3200);
DISPLAY INVISIBLE (-4650 3200);
FORCEPROP 2 LAST CDS_LIB standard
J 0
(-4975 3325);
DISPLAY INVISIBLE (-4975 3325);
FORCEPROP 2 LAST PATH I74
J 0
(-4775 3375);
DISPLAY 1.021277 (-4775 3375);
DISPLAY INVISIBLE (-4775 3375);
FORCEADD OFFPAGE..2
(-4975 3425);
FORCEPROP 2 LAST $XR0 276 
J 0
(-4786 3425);
DISPLAY 0.638298 (-4786 3425);
PAINT MONO (-4786 3425);
FORCEPROP 1 LAST COMMENT_BODY TRUE
J 0
(-5020 3330);
DISPLAY 0.872340 (-5020 3330);
PAINT GREEN (-5020 3330);
DISPLAY INVISIBLE (-5020 3330);
FORCEPROP 1 LAST OFFPAGE TRUE
J 0
(-4650 3300);
DISPLAY 0.872340 (-4650 3300);
PAINT GREEN (-4650 3300);
DISPLAY INVISIBLE (-4650 3300);
FORCEPROP 2 LAST CDS_LIB standard
J 0
(-4975 3425);
DISPLAY INVISIBLE (-4975 3425);
FORCEPROP 2 LAST PATH I75
J 0
(-4775 3475);
DISPLAY 1.021277 (-4775 3475);
DISPLAY INVISIBLE (-4775 3475);
FORCEADD Q_RES..1
(-5000 3775);
FORCEPROP 1 LAST PART_NUMBER CS00002JB13
J 0
(-5100 3825);
DISPLAY 0.489362 (-5100 3825);
PAINT BLUE (-5100 3825);
DISPLAY INVISIBLE (-5100 3825);
FORCEPROP 1 LAST PACK_TYPE 0402LF
J 0
(-5100 3875);
DISPLAY 0.489362 (-5100 3875);
PAINT SKYBLUE (-5100 3875);
FORCEPROP 1 LAST VALUE 0
J 2
(-4850 3775);
DISPLAY 0.489362 (-4850 3775);
PAINT SKYBLUE (-4850 3775);
FORCEPROP 1 LAST MATERIAL CHIP
J 0
(-4750 3775);
DISPLAY 0.489362 (-4750 3775);
PAINT SKYBLUE (-4750 3775);
FORCEPROP 1 LAST TOLERANCE 5%
J 0
(-4825 3775);
DISPLAY 0.489362 (-4825 3775);
PAINT SKYBLUE (-4825 3775);
FORCEPROP 1 LAST WATTAGE 1/16W
J 2
(-4825 3875);
DISPLAY 0.489362 (-4825 3875);
PAINT SKYBLUE (-4825 3875);
FORCEPROP 1 LAST LOCATION PR4225
J 0
(-5250 3775);
DISPLAY 0.617021 (-5250 3775);
PAINT AQUA (-5250 3775);
FORCEPROP 1 LASTPIN (-5100 3775) $PN 1
J 0
(-5088 3787);
DISPLAY 0.787234 (-5088 3787);
PAINT MONO (-5088 3787);
FORCEPROP 1 LASTPIN (-4900 3775) $PN 2
J 0
(-4938 3787);
DISPLAY 0.787234 (-4938 3787);
PAINT MONO (-4938 3787);
FORCEPROP 2 LAST CDS_LIB pure_quanta
J 0
(-5000 3775);
DISPLAY INVISIBLE (-5000 3775);
FORCEPROP 1 LAST PATH I76
J 0
(-5050 3925);
DISPLAY 0.978723 (-5050 3925);
PAINT WHITE (-5050 3925);
DISPLAY INVISIBLE (-5050 3925);
FORCEPROP 0 LAST $SEC 1
J 0
(-4825 3900);
DISPLAY 0.680851 (-4825 3900);
PAINT MONO (-4825 3900);
DISPLAY INVISIBLE (-4825 3900);
FORCEPROP 0 LAST CDS_SEC 1
J 0
(-4825 3900);
DISPLAY 1.021277 (-4825 3900);
DISPLAY INVISIBLE (-4825 3900);
FORCEADD OFFPAGE..4
(-4175 2375);
FORCEPROP 2 LAST $XR0 275 
J 0
(-3989 2375);
DISPLAY 0.638298 (-3989 2375);
PAINT MONO (-3989 2375);
FORCEPROP 1 LAST COMMENT_BODY TRUE
J 0
(-4200 2275);
DISPLAY 0.872340 (-4200 2275);
PAINT GREEN (-4200 2275);
DISPLAY INVISIBLE (-4200 2275);
FORCEPROP 1 LAST OFFPAGE TRUE
J 0
(-3850 2250);
DISPLAY 0.872340 (-3850 2250);
PAINT GREEN (-3850 2250);
DISPLAY INVISIBLE (-3850 2250);
FORCEPROP 2 LAST CDS_LIB standard
J 0
(-4175 2375);
DISPLAY INVISIBLE (-4175 2375);
FORCEPROP 2 LAST PATH I77
J 0
(-3975 2425);
DISPLAY 1.021277 (-3975 2425);
DISPLAY INVISIBLE (-3975 2425);
FORCEADD Q_RES..1
(-4700 3075);
FORCEPROP 1 LAST PART_NUMBER CS00002JB13
J 0
(-4800 3125);
DISPLAY 0.489362 (-4800 3125);
PAINT BLUE (-4800 3125);
DISPLAY INVISIBLE (-4800 3125);
FORCEPROP 1 LAST MATERIAL CHIP
J 0
(-4450 3075);
DISPLAY 0.489362 (-4450 3075);
PAINT SKYBLUE (-4450 3075);
FORCEPROP 1 LAST TOLERANCE 5%
J 0
(-4525 3075);
DISPLAY 0.489362 (-4525 3075);
PAINT SKYBLUE (-4525 3075);
FORCEPROP 1 LAST VALUE 0
J 2
(-4550 3075);
DISPLAY 0.489362 (-4550 3075);
PAINT SKYBLUE (-4550 3075);
FORCEPROP 1 LAST WATTAGE 1/16W
J 2
(-4525 3175);
DISPLAY 0.489362 (-4525 3175);
PAINT SKYBLUE (-4525 3175);
FORCEPROP 1 LAST PACK_TYPE 0402LF
J 0
(-4800 3175);
DISPLAY 0.489362 (-4800 3175);
PAINT SKYBLUE (-4800 3175);
FORCEPROP 1 LAST LOCATION R2597
J 0
(-4950 3075);
DISPLAY 0.617021 (-4950 3075);
PAINT AQUA (-4950 3075);
FORCEPROP 1 LASTPIN (-4800 3075) $PN 1
J 0
(-4788 3087);
DISPLAY 0.787234 (-4788 3087);
PAINT MONO (-4788 3087);
FORCEPROP 1 LASTPIN (-4600 3075) $PN 2
J 0
(-4638 3087);
DISPLAY 0.787234 (-4638 3087);
PAINT MONO (-4638 3087);
FORCEPROP 2 LAST CDS_LIB pure_quanta
J 0
(-4700 3075);
DISPLAY INVISIBLE (-4700 3075);
FORCEPROP 1 LAST PATH I78
J 0
(-4750 3225);
DISPLAY 0.978723 (-4750 3225);
PAINT WHITE (-4750 3225);
DISPLAY INVISIBLE (-4750 3225);
FORCEPROP 0 LAST $SEC 1
J 0
(-4525 3200);
DISPLAY 0.680851 (-4525 3200);
PAINT MONO (-4525 3200);
DISPLAY INVISIBLE (-4525 3200);
FORCEPROP 0 LAST CDS_SEC 1
J 0
(-4525 3200);
DISPLAY 1.021277 (-4525 3200);
DISPLAY INVISIBLE (-4525 3200);
FORCEADD Q_RES..2
(-4100 3325);
FORCEPROP 1 LAST PART_NUMBER CS21002FB06
J 0
(-4075 3200);
DISPLAY 0.617021 (-4075 3200);
PAINT BLUE (-4075 3200);
DISPLAY INVISIBLE (-4075 3200);
FORCEPROP 1 LAST TOLERANCE 1%
J 0
(-4070 3350);
DISPLAY 0.617021 (-4070 3350);
PAINT SKYBLUE (-4070 3350);
FORCEPROP 1 LAST WATTAGE 1/16W
J 0
(-4075 3300);
DISPLAY 0.617021 (-4075 3300);
PAINT SKYBLUE (-4075 3300);
FORCEPROP 1 LAST VALUE 1K
J 0
(-4070 3400);
DISPLAY 0.617021 (-4070 3400);
PAINT SKYBLUE (-4070 3400);
FORCEPROP 1 LAST PACK_TYPE 0402LF
J 0
(-4075 3150);
DISPLAY 0.617021 (-4075 3150);
PAINT SKYBLUE (-4075 3150);
FORCEPROP 1 LAST MATERIAL CHIP
J 0
(-4075 3250);
DISPLAY 0.617021 (-4075 3250);
PAINT RED (-4075 3250);
FORCEPROP 1 LAST LOCATION R2398
J 0
(-4070 3450);
DISPLAY 0.617021 (-4070 3450);
PAINT AQUA (-4070 3450);
FORCEPROP 1 LASTPIN (-4100 3425) $PN 1
J 0
(-4095 3387);
DISPLAY 0.617021 (-4095 3387);
PAINT MONO (-4095 3387);
FORCEPROP 1 LASTPIN (-4100 3225) $PN 2
J 0
(-4095 3235);
DISPLAY 0.617021 (-4095 3235);
PAINT MONO (-4095 3235);
FORCEPROP 1 LAST PATH I79
J 0
(-4050 3500);
DISPLAY 0.978723 (-4050 3500);
PAINT WHITE (-4050 3500);
DISPLAY INVISIBLE (-4050 3500);
FORCEPROP 2 LAST CDS_LIB pure_quanta
J 0
(-4100 3325);
DISPLAY INVISIBLE (-4100 3325);
FORCEPROP 1 LAST LOCATION R2398
J 0
(-4050 3500);
DISPLAY 1.021277 (-4050 3500);
PAINT AQUA (-4050 3500);
DISPLAY INVISIBLE (-4050 3500);
FORCEPROP 0 LAST $SEC 1
J 0
(-4050 3500);
DISPLAY 0.680851 (-4050 3500);
PAINT MONO (-4050 3500);
DISPLAY INVISIBLE (-4050 3500);
FORCEPROP 0 LAST CDS_SEC 1
J 0
(-4050 3500);
DISPLAY 1.021277 (-4050 3500);
DISPLAY INVISIBLE (-4050 3500);
FORCEADD VCC15..1
(-9550 2350);
FORCEPROP 3 LASTPIN (-9550 2300) SIG_NAME P12V_AUX\g
J 0
(-9540 2310);
DISPLAY 0.659574 (-9540 2310);
PAINT MONO (-9540 2310);
DISPLAY INVISIBLE (-9540 2310);
FORCEPROP 1 LAST HDL_POWER P12V_AUX
J 1
(-9550 2400);
DISPLAY 0.617021 (-9550 2400);
PAINT GREEN (-9550 2400);
FORCEPROP 2 LAST CDS_LIB logical_power
J 0
(-9550 2350);
DISPLAY INVISIBLE (-9550 2350);
FORCEPROP 1 LAST PATH I8
J 0
(-9500 2375);
DISPLAY 0.872340 (-9500 2375);
PAINT AQUA (-9500 2375);
DISPLAY INVISIBLE (-9500 2375);
FORCEADD UNIVERSAL_GND..1
(-4400 3700);
FORCEPROP 3 LASTPIN (-4400 3750) SIG_NAME GND\g
J 0
(-4390 3760);
DISPLAY 0.659574 (-4390 3760);
PAINT MONO (-4390 3760);
DISPLAY INVISIBLE (-4390 3760);
FORCEPROP 1 LAST HDL_POWER GND
J 1
(-4375 3625);
DISPLAY 0.872340 (-4375 3625);
PAINT GREEN (-4375 3625);
DISPLAY INVISIBLE (-4375 3625);
FORCEPROP 2 LAST CDS_LIB logical_power
J 0
(-4400 3700);
DISPLAY INVISIBLE (-4400 3700);
FORCEPROP 1 LAST PATH I80
J 0
(-4325 3700);
DISPLAY 0.872340 (-4325 3700);
PAINT AQUA (-4325 3700);
DISPLAY INVISIBLE (-4325 3700);
FORCEADD VCC15..1
(-4100 3575);
FORCEPROP 3 LASTPIN (-4100 3525) SIG_NAME P3V3_AUX\g
J 0
(-4090 3535);
DISPLAY 0.659574 (-4090 3535);
PAINT MONO (-4090 3535);
DISPLAY INVISIBLE (-4090 3535);
FORCEPROP 1 LAST HDL_POWER P3V3_AUX
J 1
(-4100 3625);
DISPLAY 0.617021 (-4100 3625);
PAINT GREEN (-4100 3625);
FORCEPROP 2 LAST CDS_LIB logical_power
J 0
(-4100 3575);
DISPLAY INVISIBLE (-4100 3575);
FORCEPROP 1 LAST PATH I81
J 0
(-4050 3600);
DISPLAY 0.872340 (-4050 3600);
PAINT AQUA (-4050 3600);
DISPLAY INVISIBLE (-4050 3600);
FORCEADD UNIVERSAL_GND..1
R 1
(-7650 7300);
FORCEPROP 3 LASTPIN (-7700 7300) SIG_NAME GND\g
J 0
(-7690 7310);
DISPLAY 0.659574 (-7690 7310);
PAINT MONO (-7690 7310);
DISPLAY INVISIBLE (-7690 7310);
FORCEPROP 1 LAST HDL_POWER GND
R 1
J 1
(-7575 7325);
DISPLAY 0.872340 (-7575 7325);
PAINT GREEN (-7575 7325);
DISPLAY INVISIBLE (-7575 7325);
FORCEPROP 2 LAST CDS_LIB logical_power
J 0
(-7650 7300);
PAINT MONO (-7650 7300);
DISPLAY INVISIBLE (-7650 7300);
FORCEPROP 1 LAST PATH I82
R 1
J 0
(-7650 7375);
DISPLAY 0.872340 (-7650 7375);
PAINT AQUA (-7650 7375);
DISPLAY INVISIBLE (-7650 7375);
FORCEADD UNIVERSAL_GND..1
R 1
(-7650 7725);
FORCEPROP 3 LASTPIN (-7700 7725) SIG_NAME GND\g
J 0
(-7690 7735);
DISPLAY 0.659574 (-7690 7735);
PAINT MONO (-7690 7735);
DISPLAY INVISIBLE (-7690 7735);
FORCEPROP 1 LAST HDL_POWER GND
R 1
J 1
(-7575 7750);
DISPLAY 0.872340 (-7575 7750);
PAINT GREEN (-7575 7750);
DISPLAY INVISIBLE (-7575 7750);
FORCEPROP 2 LAST CDS_LIB logical_power
J 0
(-7650 7725);
PAINT MONO (-7650 7725);
DISPLAY INVISIBLE (-7650 7725);
FORCEPROP 1 LAST PATH I83
R 1
J 0
(-7650 7800);
DISPLAY 0.872340 (-7650 7800);
PAINT AQUA (-7650 7800);
DISPLAY INVISIBLE (-7650 7800);
FORCEADD Q_RES..1
(-5025 4225);
FORCEPROP 1 LAST PART_NUMBER CS00002JB13
J 0
(-4925 4175);
DISPLAY 0.638298 (-4925 4175);
DISPLAY INVISIBLE (-4925 4175);
FORCEPROP 1 LAST WATTAGE 1/16W
J 2
(-4450 4225);
DISPLAY 0.638298 (-4450 4225);
FORCEPROP 1 LAST VALUE 0
J 2
(-4900 4225);
DISPLAY 0.638298 (-4900 4225);
FORCEPROP 1 LAST MATERIAL CHIP
J 0
(-5225 4175);
DISPLAY 0.638298 (-5225 4175);
FORCEPROP 1 LAST TOLERANCE 5%
J 0
(-4875 4225);
DISPLAY 0.638298 (-4875 4225);
FORCEPROP 1 LAST PACK_TYPE 0402LF
J 0
(-4800 4225);
DISPLAY 0.638298 (-4800 4225);
FORCEPROP 1 LAST LOCATION PR4224
J 0
(-5275 4225);
DISPLAY 0.638298 (-5275 4225);
FORCEPROP 1 LASTPIN (-5125 4225) $PN 1
J 0
(-5113 4237);
DISPLAY 0.787234 (-5113 4237);
PAINT MONO (-5113 4237);
FORCEPROP 1 LASTPIN (-4925 4225) $PN 2
J 0
(-4963 4237);
DISPLAY 0.787234 (-4963 4237);
PAINT MONO (-4963 4237);
FORCEPROP 2 LAST CDS_LIB pure_quanta
J 0
(-5025 4225);
DISPLAY INVISIBLE (-5025 4225);
FORCEPROP 1 LAST PATH I84
J 0
(-5075 4375);
DISPLAY 0.978723 (-5075 4375);
PAINT WHITE (-5075 4375);
DISPLAY INVISIBLE (-5075 4375);
FORCEPROP 0 LAST $SEC 1
J 0
(-4450 4275);
DISPLAY 0.680851 (-4450 4275);
PAINT MONO (-4450 4275);
DISPLAY INVISIBLE (-4450 4275);
FORCEPROP 0 LAST CDS_SEC 1
J 0
(-4450 4275);
DISPLAY 1.021277 (-4450 4275);
DISPLAY INVISIBLE (-4450 4275);
FORCEADD Q_RES..1
(-5025 4675);
FORCEPROP 1 LAST PART_NUMBER CS00002JB13
J 0
(-4925 4625);
DISPLAY 0.638298 (-4925 4625);
DISPLAY INVISIBLE (-4925 4625);
FORCEPROP 1 LAST MATERIAL CHIP
J 0
(-5225 4625);
DISPLAY 0.638298 (-5225 4625);
FORCEPROP 1 LAST VALUE 0
J 2
(-4900 4675);
DISPLAY 0.638298 (-4900 4675);
FORCEPROP 1 LAST TOLERANCE 5%
J 0
(-4875 4675);
DISPLAY 0.638298 (-4875 4675);
FORCEPROP 1 LAST PACK_TYPE 0402LF
J 0
(-4800 4675);
DISPLAY 0.638298 (-4800 4675);
FORCEPROP 1 LAST WATTAGE 1/16W
J 2
(-4450 4675);
DISPLAY 0.638298 (-4450 4675);
FORCEPROP 1 LAST LOCATION PR4223
J 0
(-5275 4675);
DISPLAY 0.638298 (-5275 4675);
FORCEPROP 1 LASTPIN (-5125 4675) $PN 1
J 0
(-5113 4687);
DISPLAY 0.787234 (-5113 4687);
PAINT MONO (-5113 4687);
FORCEPROP 1 LASTPIN (-4925 4675) $PN 2
J 0
(-4963 4687);
DISPLAY 0.787234 (-4963 4687);
PAINT MONO (-4963 4687);
FORCEPROP 2 LAST CDS_LIB pure_quanta
J 0
(-5025 4675);
DISPLAY INVISIBLE (-5025 4675);
FORCEPROP 1 LAST PATH I85
J 0
(-5075 4825);
DISPLAY 0.978723 (-5075 4825);
PAINT WHITE (-5075 4825);
DISPLAY INVISIBLE (-5075 4825);
FORCEPROP 0 LAST $SEC 1
J 0
(-4450 4725);
DISPLAY 0.680851 (-4450 4725);
PAINT MONO (-4450 4725);
DISPLAY INVISIBLE (-4450 4725);
FORCEPROP 0 LAST CDS_SEC 1
J 0
(-4450 4725);
DISPLAY 1.021277 (-4450 4725);
DISPLAY INVISIBLE (-4450 4725);
FORCEADD Q_RES..1
(-5025 5125);
FORCEPROP 1 LAST PART_NUMBER CS00002JB13
J 0
(-4925 5075);
DISPLAY 0.638298 (-4925 5075);
DISPLAY INVISIBLE (-4925 5075);
FORCEPROP 1 LAST MATERIAL CHIP
J 0
(-5225 5075);
DISPLAY 0.638298 (-5225 5075);
FORCEPROP 1 LAST VALUE 0
J 2
(-4900 5125);
DISPLAY 0.638298 (-4900 5125);
FORCEPROP 1 LAST TOLERANCE 5%
J 0
(-4875 5125);
DISPLAY 0.638298 (-4875 5125);
FORCEPROP 1 LAST PACK_TYPE 0402LF
J 0
(-4800 5125);
DISPLAY 0.638298 (-4800 5125);
FORCEPROP 1 LAST WATTAGE 1/16W
J 2
(-4450 5125);
DISPLAY 0.638298 (-4450 5125);
FORCEPROP 1 LAST LOCATION PR4222
J 0
(-5250 5125);
DISPLAY 0.638298 (-5250 5125);
FORCEPROP 1 LASTPIN (-5125 5125) $PN 1
J 0
(-5113 5137);
DISPLAY 0.787234 (-5113 5137);
PAINT MONO (-5113 5137);
FORCEPROP 1 LASTPIN (-4925 5125) $PN 2
J 0
(-4963 5137);
DISPLAY 0.787234 (-4963 5137);
PAINT MONO (-4963 5137);
FORCEPROP 2 LAST CDS_LIB pure_quanta
J 0
(-5025 5125);
DISPLAY INVISIBLE (-5025 5125);
FORCEPROP 1 LAST PATH I86
J 0
(-5075 5275);
DISPLAY 0.978723 (-5075 5275);
PAINT WHITE (-5075 5275);
DISPLAY INVISIBLE (-5075 5275);
FORCEPROP 0 LAST $SEC 1
J 0
(-4450 5175);
DISPLAY 0.680851 (-4450 5175);
PAINT MONO (-4450 5175);
DISPLAY INVISIBLE (-4450 5175);
FORCEPROP 0 LAST CDS_SEC 1
J 0
(-4450 5175);
DISPLAY 1.021277 (-4450 5175);
DISPLAY INVISIBLE (-4450 5175);
FORCEADD Q_RES..1
(-5025 5575);
FORCEPROP 1 LAST PART_NUMBER CS00002JB13
J 0
(-4925 5525);
DISPLAY 0.638298 (-4925 5525);
DISPLAY INVISIBLE (-4925 5525);
FORCEPROP 1 LAST MATERIAL CHIP
J 0
(-5225 5525);
DISPLAY 0.638298 (-5225 5525);
FORCEPROP 1 LAST VALUE 0
J 2
(-4900 5575);
DISPLAY 0.638298 (-4900 5575);
FORCEPROP 1 LAST TOLERANCE 5%
J 0
(-4875 5575);
DISPLAY 0.638298 (-4875 5575);
FORCEPROP 1 LAST PACK_TYPE 0402LF
J 0
(-4800 5575);
DISPLAY 0.638298 (-4800 5575);
FORCEPROP 1 LAST WATTAGE 1/16W
J 2
(-4450 5575);
DISPLAY 0.638298 (-4450 5575);
FORCEPROP 1 LAST LOCATION PR4221
J 0
(-5250 5575);
DISPLAY 0.638298 (-5250 5575);
FORCEPROP 1 LASTPIN (-5125 5575) $PN 1
J 0
(-5113 5587);
DISPLAY 0.787234 (-5113 5587);
PAINT MONO (-5113 5587);
FORCEPROP 1 LASTPIN (-4925 5575) $PN 2
J 0
(-4963 5587);
DISPLAY 0.787234 (-4963 5587);
PAINT MONO (-4963 5587);
FORCEPROP 2 LAST CDS_LIB pure_quanta
J 0
(-5025 5575);
DISPLAY INVISIBLE (-5025 5575);
FORCEPROP 1 LAST PATH I87
J 0
(-5075 5725);
DISPLAY 0.978723 (-5075 5725);
PAINT WHITE (-5075 5725);
DISPLAY INVISIBLE (-5075 5725);
FORCEPROP 0 LAST $SEC 1
J 0
(-4450 5625);
DISPLAY 0.680851 (-4450 5625);
PAINT MONO (-4450 5625);
DISPLAY INVISIBLE (-4450 5625);
FORCEPROP 0 LAST CDS_SEC 1
J 0
(-4450 5625);
DISPLAY 1.021277 (-4450 5625);
DISPLAY INVISIBLE (-4450 5625);
FORCEADD UNIVERSAL_GND..1
(-4400 4150);
FORCEPROP 3 LASTPIN (-4400 4200) SIG_NAME GND\g
J 0
(-4390 4210);
DISPLAY 0.659574 (-4390 4210);
PAINT MONO (-4390 4210);
DISPLAY INVISIBLE (-4390 4210);
FORCEPROP 1 LAST HDL_POWER GND
J 1
(-4375 4075);
DISPLAY 0.872340 (-4375 4075);
PAINT GREEN (-4375 4075);
DISPLAY INVISIBLE (-4375 4075);
FORCEPROP 2 LAST CDS_LIB logical_power
J 0
(-4400 4150);
DISPLAY INVISIBLE (-4400 4150);
FORCEPROP 1 LAST PATH I88
J 0
(-4325 4150);
DISPLAY 0.872340 (-4325 4150);
PAINT AQUA (-4325 4150);
DISPLAY INVISIBLE (-4325 4150);
FORCEADD UNIVERSAL_GND..1
(-4400 4600);
FORCEPROP 3 LASTPIN (-4400 4650) SIG_NAME GND\g
J 0
(-4390 4660);
DISPLAY 0.659574 (-4390 4660);
PAINT MONO (-4390 4660);
DISPLAY INVISIBLE (-4390 4660);
FORCEPROP 1 LAST HDL_POWER GND
J 1
(-4375 4525);
DISPLAY 0.872340 (-4375 4525);
PAINT GREEN (-4375 4525);
DISPLAY INVISIBLE (-4375 4525);
FORCEPROP 2 LAST CDS_LIB logical_power
J 0
(-4400 4600);
DISPLAY INVISIBLE (-4400 4600);
FORCEPROP 1 LAST PATH I89
J 0
(-4325 4600);
DISPLAY 0.872340 (-4325 4600);
PAINT AQUA (-4325 4600);
DISPLAY INVISIBLE (-4325 4600);
FORCEADD Q_RES..1
(-9275 2125);
FORCEPROP 1 LAST PART_NUMBER CS00002JB13
J 0
(-9150 2075);
DISPLAY 0.617021 (-9150 2075);
PAINT BLUE (-9150 2075);
DISPLAY INVISIBLE (-9150 2075);
FORCEPROP 1 LAST VALUE 0
J 2
(-9125 2125);
DISPLAY 0.617021 (-9125 2125);
PAINT SKYBLUE (-9125 2125);
FORCEPROP 1 LAST MATERIAL CHIP
J 0
(-9150 2025);
DISPLAY 0.617021 (-9150 2025);
PAINT SKYBLUE (-9150 2025);
FORCEPROP 1 LAST PACK_TYPE 0402LF
J 0
(-9025 2125);
DISPLAY 0.617021 (-9025 2125);
PAINT SKYBLUE (-9025 2125);
FORCEPROP 1 LAST WATTAGE 1/16W
J 2
(-8850 2025);
DISPLAY 0.617021 (-8850 2025);
PAINT SKYBLUE (-8850 2025);
FORCEPROP 1 LAST TOLERANCE 5%
J 0
(-9100 2125);
DISPLAY 0.617021 (-9100 2125);
PAINT SKYBLUE (-9100 2125);
FORCEPROP 1 LAST LOCATION PR108
J 0
(-9500 2125);
DISPLAY 0.617021 (-9500 2125);
PAINT AQUA (-9500 2125);
FORCEPROP 1 LASTPIN (-9375 2125) $PN 1
J 0
(-9363 2137);
DISPLAY 0.617021 (-9363 2137);
PAINT MONO (-9363 2137);
FORCEPROP 1 LASTPIN (-9175 2125) $PN 2
J 0
(-9213 2137);
DISPLAY 0.617021 (-9213 2137);
PAINT MONO (-9213 2137);
FORCEPROP 2 LAST CDS_LIB pure_quanta
J 0
(-9275 2125);
DISPLAY INVISIBLE (-9275 2125);
FORCEPROP 1 LAST PATH I9
J 0
(-9325 2275);
DISPLAY 0.978723 (-9325 2275);
PAINT WHITE (-9325 2275);
DISPLAY INVISIBLE (-9325 2275);
FORCEPROP 1 LAST LOCATION PR108
J 0
(-9325 2225);
DISPLAY 1.021277 (-9325 2225);
PAINT AQUA (-9325 2225);
DISPLAY INVISIBLE (-9325 2225);
FORCEPROP 0 LAST $SEC 1
J 0
(-9325 2225);
DISPLAY 0.680851 (-9325 2225);
PAINT MONO (-9325 2225);
DISPLAY INVISIBLE (-9325 2225);
FORCEPROP 0 LAST CDS_SEC 1
J 0
(-9325 2225);
DISPLAY 1.021277 (-9325 2225);
DISPLAY INVISIBLE (-9325 2225);
FORCEADD UNIVERSAL_GND..1
(-4400 5050);
FORCEPROP 3 LASTPIN (-4400 5100) SIG_NAME GND\g
J 0
(-4390 5110);
DISPLAY 0.659574 (-4390 5110);
PAINT MONO (-4390 5110);
DISPLAY INVISIBLE (-4390 5110);
FORCEPROP 1 LAST HDL_POWER GND
J 1
(-4375 4975);
DISPLAY 0.872340 (-4375 4975);
PAINT GREEN (-4375 4975);
DISPLAY INVISIBLE (-4375 4975);
FORCEPROP 2 LAST CDS_LIB logical_power
J 0
(-4400 5050);
DISPLAY INVISIBLE (-4400 5050);
FORCEPROP 1 LAST PATH I90
J 0
(-4325 5050);
DISPLAY 0.872340 (-4325 5050);
PAINT AQUA (-4325 5050);
DISPLAY INVISIBLE (-4325 5050);
FORCEADD UNIVERSAL_GND..1
(-4400 5500);
FORCEPROP 3 LASTPIN (-4400 5550) SIG_NAME GND\g
J 0
(-4390 5560);
DISPLAY 0.659574 (-4390 5560);
PAINT MONO (-4390 5560);
DISPLAY INVISIBLE (-4390 5560);
FORCEPROP 1 LAST HDL_POWER GND
J 1
(-4375 5425);
DISPLAY 0.872340 (-4375 5425);
PAINT GREEN (-4375 5425);
DISPLAY INVISIBLE (-4375 5425);
FORCEPROP 2 LAST CDS_LIB logical_power
J 0
(-4400 5500);
DISPLAY INVISIBLE (-4400 5500);
FORCEPROP 1 LAST PATH I91
J 0
(-4325 5500);
DISPLAY 0.872340 (-4325 5500);
PAINT AQUA (-4325 5500);
DISPLAY INVISIBLE (-4325 5500);
FORCEADD Q_CAP..1
(-5575 6900);
FORCEPROP 1 LAST PART_NUMBER CH6101MEB03
J 0
(-5525 6725);
DISPLAY 0.617021 (-5525 6725);
PAINT BLUE (-5525 6725);
DISPLAY INVISIBLE (-5525 6725);
FORCEPROP 1 LAST VALUE 10UF
J 0
(-5525 6975);
DISPLAY 0.617021 (-5525 6975);
PAINT SKYBLUE (-5525 6975);
FORCEPROP 1 LAST VOLTAGE 6.3V
J 0
(-5525 6925);
DISPLAY 0.617021 (-5525 6925);
PAINT SKYBLUE (-5525 6925);
FORCEPROP 1 LAST MATERIAL X6S
J 0
(-5525 6825);
DISPLAY 0.617021 (-5525 6825);
PAINT SKYBLUE (-5525 6825);
FORCEPROP 1 LAST TOLERANCE 20%
J 0
(-5525 6875);
DISPLAY 0.617021 (-5525 6875);
PAINT SKYBLUE (-5525 6875);
FORCEPROP 1 LAST PACK_TYPE C0402
J 0
(-5525 6775);
DISPLAY 0.617021 (-5525 6775);
PAINT SKYBLUE (-5525 6775);
FORCEPROP 1 LAST LOCATION PC224
J 0
(-5525 7025);
DISPLAY 0.617021 (-5525 7025);
PAINT AQUA (-5525 7025);
FORCEPROP 1 LASTPIN (-5575 7000) $PN 1
J 0
(-5565 6980);
DISPLAY 0.617021 (-5565 6980);
PAINT MONO (-5565 6980);
FORCEPROP 1 LASTPIN (-5575 6800) $PN 2
J 0
(-5565 6780);
DISPLAY 0.617021 (-5565 6780);
PAINT MONO (-5565 6780);
FORCEPROP 2 LAST CDS_LIB pure_quanta
J 0
(-5575 6900);
DISPLAY INVISIBLE (-5575 6900);
FORCEPROP 1 LAST PATH I92
J 0
(-5525 7050);
DISPLAY 0.978723 (-5525 7050);
PAINT WHITE (-5525 7050);
DISPLAY INVISIBLE (-5525 7050);
FORCEPROP 1 LAST LOCATION PC224
J 0
(-5525 7075);
DISPLAY 1.021277 (-5525 7075);
PAINT AQUA (-5525 7075);
DISPLAY INVISIBLE (-5525 7075);
FORCEPROP 0 LAST $SEC 1
J 0
(-5525 7075);
DISPLAY 0.680851 (-5525 7075);
PAINT MONO (-5525 7075);
DISPLAY INVISIBLE (-5525 7075);
FORCEPROP 0 LAST CDS_SEC 1
J 0
(-5525 7075);
DISPLAY 1.021277 (-5525 7075);
DISPLAY INVISIBLE (-5525 7075);
FORCEADD OFFPAGE..4
(-5000 6025);
FORCEPROP 2 LAST $XR0 275 
J 0
(-4814 6025);
DISPLAY 0.638298 (-4814 6025);
PAINT MONO (-4814 6025);
FORCEPROP 1 LAST COMMENT_BODY TRUE
J 0
(-5025 5925);
DISPLAY 0.872340 (-5025 5925);
PAINT GREEN (-5025 5925);
DISPLAY INVISIBLE (-5025 5925);
FORCEPROP 1 LAST OFFPAGE TRUE
J 0
(-4675 5900);
DISPLAY 0.872340 (-4675 5900);
PAINT GREEN (-4675 5900);
DISPLAY INVISIBLE (-4675 5900);
FORCEPROP 2 LAST CDS_LIB standard
J 0
(-5000 6025);
DISPLAY INVISIBLE (-5000 6025);
FORCEPROP 2 LAST PATH I93
J 0
(-4800 6075);
DISPLAY 1.021277 (-4800 6075);
DISPLAY INVISIBLE (-4800 6075);
FORCEADD OFFPAGE..2
(-5000 6125);
FORCEPROP 2 LAST $XR0 275 
J 0
(-4811 6125);
DISPLAY 0.638298 (-4811 6125);
PAINT MONO (-4811 6125);
FORCEPROP 1 LAST COMMENT_BODY TRUE
J 0
(-5045 6030);
DISPLAY 0.872340 (-5045 6030);
PAINT GREEN (-5045 6030);
DISPLAY INVISIBLE (-5045 6030);
FORCEPROP 1 LAST OFFPAGE TRUE
J 0
(-4675 6000);
DISPLAY 0.872340 (-4675 6000);
PAINT GREEN (-4675 6000);
DISPLAY INVISIBLE (-4675 6000);
FORCEPROP 2 LAST CDS_LIB standard
J 0
(-5000 6125);
DISPLAY INVISIBLE (-5000 6125);
FORCEPROP 2 LAST PATH I94
J 0
(-4800 6175);
DISPLAY 1.021277 (-4800 6175);
DISPLAY INVISIBLE (-4800 6175);
FORCEADD Q_CAP..1
(-5175 6900);
FORCEPROP 1 LAST PART_NUMBER CH5103KEB01
J 0
(-5125 6725);
DISPLAY 0.617021 (-5125 6725);
PAINT BLUE (-5125 6725);
DISPLAY INVISIBLE (-5125 6725);
FORCEPROP 1 LAST VALUE 1UF
J 0
(-5125 6975);
DISPLAY 0.617021 (-5125 6975);
PAINT SKYBLUE (-5125 6975);
FORCEPROP 1 LAST MATERIAL X6S
J 0
(-5125 6825);
DISPLAY 0.617021 (-5125 6825);
PAINT SKYBLUE (-5125 6825);
FORCEPROP 1 LAST PACK_TYPE C0402
J 0
(-5125 6775);
DISPLAY 0.617021 (-5125 6775);
PAINT SKYBLUE (-5125 6775);
FORCEPROP 1 LAST TOLERANCE 10%
J 0
(-5125 6875);
DISPLAY 0.617021 (-5125 6875);
PAINT SKYBLUE (-5125 6875);
FORCEPROP 1 LAST VOLTAGE 16V
J 0
(-5125 6925);
DISPLAY 0.617021 (-5125 6925);
PAINT SKYBLUE (-5125 6925);
FORCEPROP 1 LAST LOCATION PC1372
J 0
(-5125 7025);
DISPLAY 0.617021 (-5125 7025);
PAINT AQUA (-5125 7025);
FORCEPROP 1 LASTPIN (-5175 7000) $PN 1
J 0
(-5165 6980);
DISPLAY 0.617021 (-5165 6980);
FORCEPROP 1 LASTPIN (-5175 6800) $PN 2
J 0
(-5165 6780);
DISPLAY 0.617021 (-5165 6780);
FORCEPROP 2 LAST CDS_LIB pure_quanta
J 0
(-5175 6900);
PAINT MONO (-5175 6900);
DISPLAY INVISIBLE (-5175 6900);
FORCEPROP 1 LAST PATH I95
J 0
(-5125 7050);
DISPLAY 0.978723 (-5125 7050);
PAINT WHITE (-5125 7050);
DISPLAY INVISIBLE (-5125 7050);
FORCEPROP 2 LAST $SEC 1
J 0
(-5125 7100);
DISPLAY 0.680851 (-5125 7100);
PAINT MONO (-5125 7100);
DISPLAY INVISIBLE (-5125 7100);
FORCEPROP 2 LAST CDS_SEC 1
J 0
(-5125 7100);
DISPLAY 1.021277 (-5125 7100);
DISPLAY INVISIBLE (-5125 7100);
FORCEADD OFFPAGE..4
(-5000 6475);
FORCEPROP 2 LAST $XR0 275 
J 0
(-4814 6475);
DISPLAY 0.638298 (-4814 6475);
PAINT MONO (-4814 6475);
FORCEPROP 1 LAST COMMENT_BODY TRUE
J 0
(-5025 6375);
DISPLAY 0.872340 (-5025 6375);
PAINT GREEN (-5025 6375);
DISPLAY INVISIBLE (-5025 6375);
FORCEPROP 1 LAST OFFPAGE TRUE
J 0
(-4675 6350);
DISPLAY 0.872340 (-4675 6350);
PAINT GREEN (-4675 6350);
DISPLAY INVISIBLE (-4675 6350);
FORCEPROP 2 LAST CDS_LIB standard
J 0
(-5000 6475);
DISPLAY INVISIBLE (-5000 6475);
FORCEPROP 2 LAST PATH I96
J 0
(-4800 6525);
DISPLAY 1.021277 (-4800 6525);
DISPLAY INVISIBLE (-4800 6525);
FORCEADD OFFPAGE..2
(-5000 6575);
FORCEPROP 2 LAST $XR0 275 
J 0
(-4811 6575);
DISPLAY 0.638298 (-4811 6575);
PAINT MONO (-4811 6575);
FORCEPROP 1 LAST COMMENT_BODY TRUE
J 0
(-5045 6480);
DISPLAY 0.872340 (-5045 6480);
PAINT GREEN (-5045 6480);
DISPLAY INVISIBLE (-5045 6480);
FORCEPROP 1 LAST OFFPAGE TRUE
J 0
(-4675 6450);
DISPLAY 0.872340 (-4675 6450);
PAINT GREEN (-4675 6450);
DISPLAY INVISIBLE (-4675 6450);
FORCEPROP 2 LAST CDS_LIB standard
J 0
(-5000 6575);
DISPLAY INVISIBLE (-5000 6575);
FORCEPROP 2 LAST PATH I97
J 0
(-4800 6625);
DISPLAY 1.021277 (-4800 6625);
DISPLAY INVISIBLE (-4800 6625);
FORCEADD Q_CAP..1
(-5575 7375);
FORCEPROP 1 LAST PART_NUMBER CH4106K1B01
J 0
(-5525 7200);
DISPLAY 0.617021 (-5525 7200);
PAINT BLUE (-5525 7200);
DISPLAY INVISIBLE (-5525 7200);
FORCEPROP 1 LAST TOLERANCE 10%
J 0
(-5525 7350);
DISPLAY 0.617021 (-5525 7350);
PAINT SKYBLUE (-5525 7350);
FORCEPROP 1 LAST PACK_TYPE C0402
J 0
(-5525 7250);
DISPLAY 0.617021 (-5525 7250);
PAINT SKYBLUE (-5525 7250);
FORCEPROP 1 LAST MATERIAL EMPTY
J 0
(-5525 7300);
DISPLAY 0.617021 (-5525 7300);
PAINT RED (-5525 7300);
FORCEPROP 1 LAST VOLTAGE 50V
J 0
(-5525 7400);
DISPLAY 0.617021 (-5525 7400);
PAINT SKYBLUE (-5525 7400);
FORCEPROP 1 LAST VALUE 100NF
J 0
(-5525 7450);
DISPLAY 0.617021 (-5525 7450);
PAINT SKYBLUE (-5525 7450);
FORCEPROP 1 LAST LOCATION PC223
J 0
(-5525 7500);
DISPLAY 0.617021 (-5525 7500);
PAINT AQUA (-5525 7500);
FORCEPROP 1 LASTPIN (-5575 7475) $PN 1
J 0
(-5565 7455);
DISPLAY 0.617021 (-5565 7455);
PAINT MONO (-5565 7455);
FORCEPROP 1 LASTPIN (-5575 7275) $PN 2
J 0
(-5565 7255);
DISPLAY 0.617021 (-5565 7255);
PAINT MONO (-5565 7255);
FORCEPROP 2 LAST CDS_LIB pure_quanta
J 0
(-5575 7375);
DISPLAY INVISIBLE (-5575 7375);
FORCEPROP 1 LAST PATH I98
J 0
(-5525 7525);
DISPLAY 0.978723 (-5525 7525);
PAINT WHITE (-5525 7525);
DISPLAY INVISIBLE (-5525 7525);
FORCEPROP 1 LAST LOCATION PC223
J 0
(-5525 7550);
DISPLAY 1.021277 (-5525 7550);
PAINT AQUA (-5525 7550);
DISPLAY INVISIBLE (-5525 7550);
FORCEPROP 0 LAST $SEC 1
J 0
(-5525 7550);
DISPLAY 0.680851 (-5525 7550);
PAINT MONO (-5525 7550);
DISPLAY INVISIBLE (-5525 7550);
FORCEPROP 0 LAST CDS_SEC 1
J 0
(-5525 7550);
DISPLAY 1.021277 (-5525 7550);
DISPLAY INVISIBLE (-5525 7550);
FORCEADD Q_CAP..1
(-5175 7375);
FORCEPROP 1 LAST PART_NUMBER CH5103KEB01
J 0
(-5125 7200);
DISPLAY 0.617021 (-5125 7200);
PAINT BLUE (-5125 7200);
DISPLAY INVISIBLE (-5125 7200);
FORCEPROP 1 LAST TOLERANCE 10%
J 0
(-5125 7350);
DISPLAY 0.617021 (-5125 7350);
PAINT SKYBLUE (-5125 7350);
FORCEPROP 1 LAST MATERIAL X6S
J 0
(-5125 7300);
DISPLAY 0.617021 (-5125 7300);
PAINT SKYBLUE (-5125 7300);
FORCEPROP 1 LAST PACK_TYPE C0402
J 0
(-5125 7250);
DISPLAY 0.617021 (-5125 7250);
PAINT SKYBLUE (-5125 7250);
FORCEPROP 1 LAST VALUE 1UF
J 0
(-5125 7450);
DISPLAY 0.617021 (-5125 7450);
PAINT SKYBLUE (-5125 7450);
FORCEPROP 1 LAST VOLTAGE 16V
J 0
(-5125 7400);
DISPLAY 0.617021 (-5125 7400);
PAINT SKYBLUE (-5125 7400);
FORCEPROP 1 LAST LOCATION PC225
J 0
(-5125 7500);
DISPLAY 0.617021 (-5125 7500);
PAINT AQUA (-5125 7500);
FORCEPROP 1 LASTPIN (-5175 7475) $PN 1
J 0
(-5165 7455);
DISPLAY 0.617021 (-5165 7455);
PAINT MONO (-5165 7455);
FORCEPROP 1 LASTPIN (-5175 7275) $PN 2
J 0
(-5165 7255);
DISPLAY 0.617021 (-5165 7255);
PAINT MONO (-5165 7255);
FORCEPROP 2 LAST CDS_LIB pure_quanta
J 0
(-5175 7375);
DISPLAY INVISIBLE (-5175 7375);
FORCEPROP 1 LAST PATH I99
J 0
(-5125 7525);
DISPLAY 0.978723 (-5125 7525);
PAINT WHITE (-5125 7525);
DISPLAY INVISIBLE (-5125 7525);
FORCEPROP 1 LAST LOCATION PC225
J 0
(-5125 7550);
DISPLAY 1.021277 (-5125 7550);
PAINT AQUA (-5125 7550);
DISPLAY INVISIBLE (-5125 7550);
FORCEPROP 0 LAST $SEC 1
J 0
(-5125 7550);
DISPLAY 0.680851 (-5125 7550);
PAINT MONO (-5125 7550);
DISPLAY INVISIBLE (-5125 7550);
FORCEPROP 0 LAST CDS_SEC 1
J 0
(-5125 7550);
DISPLAY 1.021277 (-5125 7550);
DISPLAY INVISIBLE (-5125 7550);
FORCEADD QUANTA_TITLE_BLOCK_C..1
(-2300 1350);
FORCEPROP 0 LAST CDS_CON_LAST_MODIFIED Fri Aug 25 14:04:45 2023
J 0
(-4185 1365);
DISPLAY INVISIBLE (-4185 1365);
FORCEPROP 1 LAST CUSTOM_TXT_CDS <CON_LAST_MODIFIED>
J 0
(-4185 1365);
DISPLAY 0.978723 (-4185 1365);
FORCEPROP 2 LAST CUSTOM_TXT_CDS <XR_PAGE_TITLE>
J 0
(-10190 6600);
DISPLAY 0.638298 (-10190 6600);
PAINT PINK (-10190 6600);
DISPLAY INVISIBLE (-10190 6600);
FORCEPROP 1 LAST CUSTOM_TXT_CDS <NAME_2>
J 0
(-5475 1400);
FORCEPROP 1 LAST CUSTOM_TXT_CDS <NAME_1>
J 0
(-5475 1525);
FORCEPROP 1 LAST CUSTOM_TXT_CDS <Q_NUMBER>
J 0
(-3703 1453);
DISPLAY 1.212766 (-3703 1453);
FORCEPROP 1 LAST CUSTOM_TXT_CDS <Q_PROJ>
J 0
(-4682 1452);
DISPLAY 1.212766 (-4682 1452);
FORCEPROP 1 LAST CUSTOM_TXT_CDS <Q_REV>
J 0
(-2484 1453);
DISPLAY 1.212766 (-2484 1453);
FORCEPROP 1 LAST CUSTOM_TXT_CDS <CON_PAGE_NUM> OF <CON_TOTAL_PAGES>
J 0
(-2746 1368);
DISPLAY 0.978723 (-2746 1368);
FORCEPROP 1 LAST Q_TITLE VCCINFAON/VCCFA_EHV CPU0 VR(1/3)
J 0
(-11600 1400);
DISPLAY 2.446809 (-11600 1400);
PAINT GREEN (-11600 1400);
FORCEPROP 1 LAST Q_DEPT 
J 1
(-6063 1399);
DISPLAY 1.957447 (-6063 1399);
PAINT GREEN (-6063 1399);
FORCEPROP 2 LAST CDS_XR_PAGE_TITLE CR-274 : @S9S_MB_2U_LIB.S9S_MB_2U(SCH_1):PAGE274
J 0
(-10190 6600);
DISPLAY 0.638298 (-10190 6600);
PAINT PINK (-10190 6600);
DISPLAY INVISIBLE (-10190 6600);
FORCEPROP 2 LAST PAGE_BORDER TRUE
J 0
(-10190 6600);
DISPLAY 0.638298 (-10190 6600);
PAINT PINK (-10190 6600);
DISPLAY INVISIBLE (-10190 6600);
FORCEPROP 1 LAST CDS_LMAN_SYM_OUTLINE -9475,6775,100,-125
J 0
(-2300 1350);
DISPLAY 0.468085 (-2300 1350);
PAINT GREEN (-2300 1350);
DISPLAY INVISIBLE (-2300 1350);
FORCEPROP 2 LAST CDS_LIB pure_quanta
J 0
(-2300 1350);
DISPLAY INVISIBLE (-2300 1350);
FORCEPROP 1 LAST COMMENT_BODY TRUE
J 0
(-2288 1337);
DISPLAY 0.978723 (-2288 1337);
PAINT GREEN (-2288 1337);
DISPLAY INVISIBLE (-2288 1337);
FORCEADD DNS..1
(-5900 7375);
PAINT RED (-5900 7375);
FORCEPROP 1 LAST COMMENT_BODY TRUE
R 1
J 0
(-5825 7150);
DISPLAY 0.872340 (-5825 7150);
PAINT GREEN (-5825 7150);
DISPLAY INVISIBLE (-5825 7150);
FORCEPROP 2 LAST CDS_LIB mstr_misc
J 0
(-5900 7375);
DISPLAY INVISIBLE (-5900 7375);
FORCEADD DNS..1
(-5550 7375);
PAINT RED (-5550 7375);
FORCEPROP 2 LAST CDS_LIB mstr_misc
J 0
(-5550 7375);
DISPLAY INVISIBLE (-5550 7375);
FORCEPROP 1 LAST COMMENT_BODY TRUE
R 1
J 0
(-5475 7150);
DISPLAY 0.872340 (-5475 7150);
PAINT GREEN (-5475 7150);
DISPLAY INVISIBLE (-5475 7150);
FORCEADD DNS..1
(-8450 1925);
PAINT RED (-8450 1925);
FORCEPROP 1 LAST COMMENT_BODY TRUE
R 1
J 0
(-8375 1700);
DISPLAY 0.872340 (-8375 1700);
PAINT GREEN (-8375 1700);
DISPLAY INVISIBLE (-8375 1700);
FORCEPROP 2 LAST CDS_LIB mstr_misc
J 0
(-8450 1925);
DISPLAY INVISIBLE (-8450 1925);
FORCEADD DNS..1
(-8075 1900);
PAINT RED (-8075 1900);
FORCEPROP 1 LAST COMMENT_BODY TRUE
R 1
J 0
(-8000 1675);
DISPLAY 0.872340 (-8000 1675);
PAINT GREEN (-8000 1675);
DISPLAY INVISIBLE (-8000 1675);
FORCEPROP 2 LAST CDS_LIB mstr_misc
J 0
(-8075 1900);
DISPLAY INVISIBLE (-8075 1900);
FORCEADD DNS..2
(-9850 2475);
PAINT RED (-9850 2475);
FORCEPROP 1 LAST COMMENT_BODY TRUE
R 1
J 0
(-9775 2250);
DISPLAY 0.872340 (-9775 2250);
PAINT GREEN (-9775 2250);
DISPLAY INVISIBLE (-9775 2250);
FORCEPROP 2 LAST CDS_LIB mstr_misc
J 0
(-9850 2475);
PAINT MONO (-9850 2475);
DISPLAY INVISIBLE (-9850 2475);
FORCEADD DNS..1
(-9275 2250);
PAINT RED (-9275 2250);
FORCEPROP 1 LAST COMMENT_BODY TRUE
R 1
J 0
(-9200 2025);
DISPLAY 0.872340 (-9200 2025);
PAINT GREEN (-9200 2025);
DISPLAY INVISIBLE (-9200 2025);
FORCEPROP 2 LAST CDS_LIB mstr_misc
J 0
(-9275 2250);
DISPLAY INVISIBLE (-9275 2250);
FORCEADD DNS..1
(-8225 2950);
PAINT RED (-8225 2950);
FORCEPROP 1 LAST COMMENT_BODY TRUE
R 1
J 0
(-8150 2725);
DISPLAY 0.872340 (-8150 2725);
PAINT GREEN (-8150 2725);
DISPLAY INVISIBLE (-8150 2725);
FORCEPROP 2 LAST CDS_LIB mstr_misc
J 0
(-8225 2950);
DISPLAY INVISIBLE (-8225 2950);
FORCEADD DNS..2
(-10350 7225);
PAINT RED (-10350 7225);
FORCEPROP 1 LAST COMMENT_BODY TRUE
R 1
J 0
(-10275 7000);
DISPLAY 0.872340 (-10275 7000);
PAINT GREEN (-10275 7000);
DISPLAY INVISIBLE (-10275 7000);
FORCEPROP 2 LAST CDS_LIB mstr_misc
J 0
(-10350 7225);
DISPLAY INVISIBLE (-10350 7225);
FORCEADD DNS..2
(-10350 7325);
PAINT RED (-10350 7325);
FORCEPROP 1 LAST COMMENT_BODY TRUE
R 1
J 0
(-10275 7100);
DISPLAY 0.872340 (-10275 7100);
PAINT GREEN (-10275 7100);
DISPLAY INVISIBLE (-10275 7100);
FORCEPROP 2 LAST CDS_LIB mstr_misc
J 0
(-10350 7325);
DISPLAY INVISIBLE (-10350 7325);
FORCEADD DNS..1
(-8350 7750);
PAINT RED (-8350 7750);
FORCEPROP 1 LAST COMMENT_BODY TRUE
R 1
J 0
(-8275 7525);
DISPLAY 0.872340 (-8275 7525);
PAINT GREEN (-8275 7525);
DISPLAY INVISIBLE (-8275 7525);
FORCEPROP 2 LAST CDS_LIB mstr_misc
J 0
(-8350 7750);
DISPLAY INVISIBLE (-8350 7750);
FORCEADD DNS..1
(-5175 2175);
PAINT RED (-5175 2175);
FORCEPROP 1 LAST COMMENT_BODY TRUE
R 1
J 0
(-5100 1950);
DISPLAY 0.872340 (-5100 1950);
PAINT GREEN (-5100 1950);
DISPLAY INVISIBLE (-5100 1950);
FORCEPROP 2 LAST CDS_LIB mstr_misc
J 0
(-5175 2175);
DISPLAY INVISIBLE (-5175 2175);
FORCEADD DNS..1
(-3675 2475);
PAINT RED (-3675 2475);
FORCEPROP 1 LAST COMMENT_BODY TRUE
R 1
J 0
(-3600 2250);
DISPLAY 0.872340 (-3600 2250);
PAINT GREEN (-3600 2250);
DISPLAY INVISIBLE (-3600 2250);
FORCEPROP 2 LAST CDS_LIB mstr_misc
J 0
(-3675 2475);
DISPLAY INVISIBLE (-3675 2475);
WIRE 16 -1 (-9325 5825)(-9325 5725);
WIRE 16 -1 (-9550 2225)(-9550 2300);
WIRE 16 -1 (-9550 2125)(-9550 2225);
WIRE 16 -1 (-9375 2225)(-9550 2225);
WIRE 16 -1 (-9500 2925)(-9500 2975);
WIRE 16 -1 (-9500 2925)(-9125 2925);
WIRE 16 -1 (-9350 3650)(-9350 3575);
WIRE 16 -1 (-11100 7325)(-11100 7400);
WIRE 16 -1 (-10650 7325)(-11100 7325);
WIRE 16 -1 (-9325 4725)(-9325 4625);
WIRE 16 -1 (-9625 7725)(-9625 7775);
WIRE 16 -1 (-9625 7725)(-9300 7725);
WIRE 16 -1 (-4100 3525)(-4100 3425);
WIRE 16 -1 (-4375 7650)(-4375 7575);
WIRE 16 -1 (-8500 1725)(-8500 1675);
WIRE 16 -1 (-8825 1725)(-8500 1725);
WIRE 16 -1 (-8500 1825)(-8500 1725);
WIRE 16 -1 (-9750 2150)(-9750 2075);
WIRE 16 -1 (-9350 3950)(-9350 3900);
WIRE 16 -1 (-9350 3950)(-9775 3950);
WIRE 16 -1 (-9350 5050)(-9350 5000);
WIRE 16 -1 (-9350 5050)(-9775 5050);
WIRE 16 -1 (-7750 1725)(-7750 1675);
WIRE 16 -1 (-8075 1725)(-7750 1725);
WIRE 16 -1 (-7750 1825)(-7750 1725);
WIRE 16 -1 (-7575 1950)(-7575 2025);
WIRE 16 -1 (-8125 2925)(-7575 2925);
WIRE 16 -1 (-8125 3050)(-7575 3050);
WIRE 16 -1 (-6000 2025)(-6000 2100);
WIRE 16 -1 (-5250 1975)(-5250 2075);
WIRE 16 -1 (-5575 2825)(-5000 2825);
WIRE 16 -1 (-4400 3775)(-4400 3750);
WIRE 16 -1 (-4900 3775)(-4400 3775);
WIRE 16 -1 (-8275 7300)(-7700 7300);
WIRE 16 -1 (-8250 7725)(-7700 7725);
WIRE 16 -1 (-4400 4225)(-4400 4200);
WIRE 16 -1 (-4925 4225)(-4400 4225);
WIRE 16 -1 (-4400 4675)(-4400 4650);
WIRE 16 -1 (-4925 4675)(-4400 4675);
WIRE 16 -1 (-4400 5125)(-4400 5100);
WIRE 16 -1 (-4925 5125)(-4400 5125);
WIRE 16 -1 (-4400 5575)(-4400 5550);
WIRE 16 -1 (-4925 5575)(-4400 5575);
WIRE 16 -1 (-4775 6700)(-5175 6700);
WIRE 16 -1 (-4775 7175)(-5175 7175);
WIRE 16 -1 (-3750 2275)(-3750 2375);
WIRE 17 273 (-4100 7975)(-2350 7975);
WIRE 17 273 (-2350 7975)(-2350 6525);
WIRE 17 273 (-4100 7975)(-4100 6525);
WIRE 17 273 (-4100 6525)(-2350 6525);
WIRE 17 273 (-4100 6475)(-2354 6475);
WIRE 17 273 (-2354 6475)(-2354 5075);
WIRE 17 273 (-4100 6475)(-4100 5075);
WIRE 17 273 (-4100 5075)(-2354 5075);
WIRE 16 -1 (-5275 5675)(-6150 5675);
FORCEPROP 2 LAST SIG_NAME NC_PVCCINFAON_CPU0_APWM3
J 0
(-6035 5685);
DISPLAY 0.617021 (-6035 5685);
WIRE 16 -1 (-7500 5275)(-7700 5275);
WIRE 16 -1 (-7700 5200)(-7700 5275);
WIRE 16 -1 (-8400 5300)(-8400 5200);
WIRE 16 -1 (-7700 5200)(-8400 5200);
WIRE 16 -1 (-11050 5200)(-10125 5200);
FORCEPROP 2 LAST SIG_NAME VSENSE_PVCCINFAON_CPU0_DN
J 0
(-10960 5210);
DISPLAY 0.617021 (-10960 5210);
WIRE 16 -1 (-10125 5200)(-8400 5200);
WIRE 16 -1 (-10125 5050)(-9975 5050);
WIRE 16 -1 (-10125 5050)(-10125 5200);
WIRE 16 -1 (-5025 3425)(-6150 3425);
FORCEPROP 2 LAST SIG_NAME PVCCFA_EHV_CPU0_BPWM1
J 0
(-5985 3435);
DISPLAY 0.617021 (-5985 3435);
WIRE 16 -1 (-5025 3325)(-6150 3325);
FORCEPROP 2 LAST SIG_NAME PVCCFA_EHV_CPU0_BCSP1
J 0
(-5985 3335);
DISPLAY 0.617021 (-5985 3335);
WIRE 16 -1 (-6150 3075)(-4800 3075);
FORCEPROP 2 LAST SIG_NAME IRQ_PVCCFA_CPU0_VRHOT_N
J 0
(-5985 3085);
DISPLAY 0.617021 (-5985 3085);
WIRE 16 -1 (-8550 3050)(-8325 3050);
WIRE 16 -1 (-8550 3175)(-8550 3050);
WIRE 16 -1 (-8925 3175)(-8550 3175);
WIRE 16 -1 (-8550 3175)(-7500 3175);
FORCEPROP 2 LAST SIG_NAME PVCCFA_EHV_CPU0_EN_R
J 0
(-8460 3185);
DISPLAY 0.617021 (-8460 3185);
WIRE 16 -1 (-9100 6425)(-7500 6425);
FORCEPROP 2 LAST SIG_NAME SMB_CLK_PVCCINFAON_CPU0
J 0
(-8535 6435);
DISPLAY 0.617021 (-8535 6435);
WIRE 16 -1 (-9100 6975)(-7500 6975);
FORCEPROP 2 LAST SIG_NAME SVID_DIO_PVCCINFAON_CPU0_R
J 0
(-8535 6985);
DISPLAY 0.617021 (-8535 6985);
WIRE 16 -1 (-9100 6825)(-7500 6825);
FORCEPROP 2 LAST SIG_NAME SVID_ALERT_PVCCINFAON_CPU0_R
J 0
(-8535 6835);
DISPLAY 0.617021 (-8535 6835);
WIRE 16 -1 (-8925 2775)(-8550 2775);
WIRE 16 -1 (-8550 2775)(-7500 2775);
FORCEPROP 2 LAST SIG_NAME PWRGD_PVCCFA_EHV_CPU0_R
J 0
(-8460 2785);
DISPLAY 0.617021 (-8460 2785);
WIRE 16 -1 (-8550 2925)(-8925 2925);
WIRE 16 -1 (-8550 2925)(-8550 2775);
WIRE 16 -1 (-8325 2925)(-8550 2925);
WIRE 16 -1 (-9100 7125)(-7500 7125);
FORCEPROP 2 LAST SIG_NAME SVID_CLK_PVCCINFAON_CPU0_R
J 0
(-8535 7135);
DISPLAY 0.617021 (-8535 7135);
WIRE 16 -1 (-8600 6125)(-7500 6125);
FORCEPROP 2 LAST SIG_NAME NC_PVCCINFAON_CPU0_SMB_ALERT
J 0
(-8535 6135);
DISPLAY 0.617021 (-8535 6135);
WIRE 16 -1 (-9100 7425)(-8675 7425);
WIRE 16 -1 (-8675 7425)(-7500 7425);
FORCEPROP 2 LAST SIG_NAME PVCCINFAON_CPU0_EN_R
J 0
(-8535 7435);
DISPLAY 0.617021 (-8535 7435);
WIRE 16 -1 (-8675 7425)(-8675 7300);
WIRE 16 -1 (-8475 7300)(-8675 7300);
WIRE 16 -1 (-9100 6275)(-7500 6275);
FORCEPROP 2 LAST SIG_NAME SMB_DIO_PVCCINFAON_CPU0
J 0
(-8535 6285);
DISPLAY 0.617021 (-8535 6285);
WIRE 16 -1 (-7500 5525)(-7700 5525);
WIRE 16 -1 (-7700 5575)(-7700 5525);
WIRE 16 -1 (-8400 5500)(-8400 5575);
WIRE 16 -1 (-7700 5575)(-8400 5575);
FORCEPROP 2 LAST SIG_NAME SH_PVCCINFAON_CPU0_R
J 0
(-8310 5585);
DISPLAY 0.617021 (-8310 5585);
WIRE 16 -1 (-8750 5575)(-8400 5575);
WIRE 16 -1 (-8675 7575)(-9100 7575);
WIRE 16 -1 (-8675 7575)(-7500 7575);
FORCEPROP 2 LAST SIG_NAME PWRGD_PVCCINFAON_CPU0_R
J 0
(-8535 7585);
DISPLAY 0.617021 (-8535 7585);
WIRE 16 -1 (-8675 7725)(-9100 7725);
WIRE 16 -1 (-8675 7575)(-8675 7725);
WIRE 16 -1 (-8450 7725)(-8675 7725);
WIRE 16 -1 (-8500 2025)(-8500 2225);
WIRE 16 -1 (-8500 2225)(-7500 2225);
FORCEPROP 2 LAST SIG_NAME PVCCINFAON_CPU0_CSPIN
J 0
(-8460 2235);
DISPLAY 0.617021 (-8460 2235);
WIRE 16 -1 (-9175 2225)(-8825 2225);
WIRE 16 -1 (-8500 2225)(-8825 2225);
WIRE 16 -1 (-8825 2025)(-8825 2225);
WIRE 16 -1 (-7750 2025)(-7750 2125);
WIRE 16 -1 (-7750 2125)(-7500 2125);
WIRE 16 -1 (-8075 2025)(-8075 2125);
WIRE 16 -1 (-8075 2125)(-7750 2125);
WIRE 16 -1 (-9175 2125)(-8075 2125);
FORCEPROP 2 LAST SIG_NAME PVCCINFAON_CPU0_VIN_CSNIN
J 0
(-8460 2135);
DISPLAY 0.617021 (-8460 2135);
WIRE 16 -1 (-8550 3475)(-8925 3475);
WIRE 16 -1 (-8550 3325)(-8550 3475);
WIRE 16 -1 (-8550 3325)(-7500 3325);
FORCEPROP 2 LAST SIG_NAME PVCCINFAON_CPU0_PIN_ALERT
J 0
(-8460 3335);
DISPLAY 0.617021 (-8460 3335);
WIRE 16 -1 (-7500 4425)(-7700 4425);
WIRE 16 -1 (-7700 4475)(-7700 4425);
WIRE 16 -1 (-8400 4400)(-8400 4475);
WIRE 16 -1 (-7700 4475)(-8400 4475);
FORCEPROP 2 LAST SIG_NAME SH_PVCCFA_EHV_CPU0_R
J 0
(-8310 4485);
DISPLAY 0.617021 (-8310 4485);
WIRE 16 -1 (-8750 4475)(-8400 4475);
WIRE 16 -1 (-7700 4175)(-7500 4175);
WIRE 16 -1 (-7700 4100)(-7700 4175);
WIRE 16 -1 (-8400 4200)(-8400 4100);
WIRE 16 -1 (-7700 4100)(-8400 4100);
WIRE 16 -1 (-11050 4100)(-10125 4100);
FORCEPROP 2 LAST SIG_NAME VSENSE_PVCCFA_EHV_CPU0_DN
J 0
(-10960 4110);
DISPLAY 0.617021 (-10960 4110);
WIRE 16 -1 (-10125 4100)(-8400 4100);
WIRE 16 -1 (-10125 3950)(-9975 3950);
WIRE 16 -1 (-10125 3950)(-10125 4100);
WIRE 16 -1 (-8925 3575)(-7500 3575);
FORCEPROP 2 LAST SIG_NAME PVCCINFAON_CPU0_VR_FAULT
J 0
(-8460 3585);
DISPLAY 0.617021 (-8460 3585);
WIRE 16 -1 (-7575 2025)(-7500 2025);
WIRE 16 -1 (-9775 2475)(-9750 2475);
WIRE 16 -1 (-9750 2475)(-7500 2475);
FORCEPROP 2 LAST SIG_NAME PVCCINFAON_CPU0_ADDR
J 0
(-8460 2485);
DISPLAY 0.617021 (-8460 2485);
WIRE 16 -1 (-9750 2350)(-9750 2475);
WIRE 16 -1 (-6150 2375)(-6000 2375);
WIRE 16 -1 (-6000 2300)(-6000 2375);
WIRE 16 -1 (-5250 2375)(-6000 2375);
WIRE 16 -1 (-4225 2375)(-5250 2375);
FORCEPROP 2 LAST SIG_NAME PVCCINFAON_CPU0_ATSEN
J 0
(-4885 2385);
DISPLAY 0.617021 (-4885 2385);
WIRE 16 -1 (-5250 2275)(-5250 2375);
WIRE 16 -1 (-6150 4225)(-5125 4225);
FORCEPROP 2 LAST SIG_NAME NC_PVCCINFAON_CPU0_ACSP6
J 0
(-6035 4235);
DISPLAY 0.617021 (-6035 4235);
WIRE 16 -1 (-5275 4325)(-6150 4325);
FORCEPROP 2 LAST SIG_NAME NC_PVCCINFAON_CPU0_APWM6
J 0
(-6035 4335);
DISPLAY 0.617021 (-6035 4335);
WIRE 16 -1 (-6150 4675)(-5125 4675);
FORCEPROP 2 LAST SIG_NAME NC_PVCCINFAON_CPU0_ACSP5
J 0
(-6035 4685);
DISPLAY 0.617021 (-6035 4685);
WIRE 16 -1 (-5275 4775)(-6150 4775);
FORCEPROP 2 LAST SIG_NAME NC_PVCCINFAON_CPU0_APWM5
J 0
(-6035 4785);
DISPLAY 0.617021 (-6035 4785);
WIRE 16 -1 (-6150 6575)(-5050 6575);
FORCEPROP 2 LAST SIG_NAME PVCCINFAON_CPU0_APWM1
J 0
(-5985 6585);
DISPLAY 0.617021 (-5985 6585);
WIRE 16 -1 (-6150 3775)(-5100 3775);
FORCEPROP 2 LAST SIG_NAME NC_PVCCINFAON_CPU0_ACSP7
J 0
(-6035 3785);
DISPLAY 0.617021 (-6035 3785);
WIRE 16 -1 (-3750 2575)(-3750 2675);
WIRE 16 -1 (-3375 2675)(-3750 2675);
WIRE 16 -1 (-6000 2675)(-6150 2675);
WIRE 16 -1 (-3750 2675)(-6000 2675);
FORCEPROP 2 LAST SIG_NAME PVCCFA_EHV_CPU0_BTSEN
J 0
(-4360 2685);
DISPLAY 0.617021 (-4360 2685);
WIRE 16 -1 (-6000 2675)(-6000 2825);
WIRE 16 -1 (-6000 2825)(-5775 2825);
WIRE 16 -1 (-5175 7000)(-5175 7100);
WIRE 16 -1 (-5175 7100)(-4775 7100);
WIRE 16 -1 (-5575 7000)(-5575 7100);
WIRE 16 -1 (-5175 7100)(-5575 7100);
WIRE 16 -1 (-5575 7100)(-6000 7100);
FORCEPROP 2 LAST SIG_NAME PVCCINFAON_CPU0_VREF
J 0
(-5960 7110);
DISPLAY 0.617021 (-5960 7110);
WIRE 16 -1 (-6000 7275)(-6000 7100);
WIRE 16 -1 (-6150 7275)(-6000 7275);
WIRE 16 -1 (-5050 6125)(-6150 6125);
FORCEPROP 2 LAST SIG_NAME PVCCINFAON_CPU0_APWM2
J 0
(-5985 6135);
DISPLAY 0.617021 (-5985 6135);
WIRE 16 -1 (-5275 3875)(-6150 3875);
FORCEPROP 2 LAST SIG_NAME NC_PVCCINFAON_CPU0_APWM7
J 0
(-6035 3885);
DISPLAY 0.617021 (-6035 3885);
WIRE 16 -1 (-5275 5225)(-6150 5225);
FORCEPROP 2 LAST SIG_NAME NC_PVCCINFAON_CPU0_APWM4
J 0
(-6035 5235);
DISPLAY 0.617021 (-6035 5235);
WIRE 16 -1 (-6150 5125)(-5125 5125);
FORCEPROP 2 LAST SIG_NAME NC_PVCCINFAON_CPU0_ACSP4
J 0
(-6035 5135);
DISPLAY 0.617021 (-6035 5135);
WIRE 16 -1 (-6150 5575)(-5125 5575);
FORCEPROP 2 LAST SIG_NAME NC_PVCCINFAON_CPU0_ACSP3
J 0
(-6035 5585);
DISPLAY 0.617021 (-6035 5585);
WIRE 16 -1 (-6150 6025)(-5050 6025);
FORCEPROP 2 LAST SIG_NAME PVCCINFAON_CPU0_ACSP2
J 0
(-5985 6035);
DISPLAY 0.617021 (-5985 6035);
WIRE 16 -1 (-6150 7575)(-5925 7575);
FORCEPROP 2 LAST SIG_NAME PVCCINFAON_CPU0_VCC
J 0
(-5960 7585);
DISPLAY 0.617021 (-5960 7585);
WIRE 16 -1 (-5925 7475)(-5925 7575);
WIRE 16 -1 (-5925 7575)(-5575 7575);
WIRE 16 -1 (-5575 7475)(-5575 7575);
WIRE 16 -1 (-5575 7575)(-5175 7575);
WIRE 16 -1 (-4950 7575)(-5175 7575);
WIRE 16 -1 (-5175 7475)(-5175 7575);
WIRE 16 -1 (-6150 6475)(-5050 6475);
FORCEPROP 2 LAST SIG_NAME PVCCINFAON_CPU0_ACSP1
J 0
(-5985 6485);
DISPLAY 0.617021 (-5985 6485);
WIRE 16 -1 (-5175 6700)(-5175 6800);
WIRE 16 -1 (-5575 6700)(-5175 6700);
WIRE 16 -1 (-5575 6800)(-5575 6700);
WIRE 16 -1 (-5175 7275)(-5175 7175);
WIRE 16 -1 (-5575 7275)(-5575 7175);
WIRE 16 -1 (-5575 7175)(-5175 7175);
WIRE 16 -1 (-5925 7175)(-5575 7175);
WIRE 16 -1 (-5925 7275)(-5925 7175);
WIRE 16 -1 (-4375 7575)(-4750 7575);
WIRE 16 -1 (-9125 3575)(-9350 3575);
WIRE 16 -1 (-9350 3575)(-9350 3475);
WIRE 16 -1 (-9125 3475)(-9350 3475);
WIRE 16 -1 (-10650 7225)(-10475 7225);
WIRE 16 -1 (-10650 7225)(-10650 7325);
WIRE 16 -1 (-10650 7325)(-10475 7325);
WIRE 16 -1 (-8825 1825)(-8825 1725);
WIRE 16 -1 (-9325 4625)(-9725 4625);
WIRE 16 -1 (-9325 5725)(-9725 5725);
WIRE 16 -1 (-8075 1825)(-8075 1725);
WIRE 16 -1 (-9550 2125)(-9375 2125);
WIRE 16 -1 (-4600 3075)(-4100 3075);
WIRE 16 -1 (-3375 3075)(-4100 3075);
FORCEPROP 2 LAST SIG_NAME IRQ_PVCCFA_CPU0_VRHOT_R_N
J 0
(-4085 3085);
DISPLAY 0.617021 (-4085 3085);
WIRE 16 -1 (-4100 3225)(-4100 3075);
WIRE 16 2175 (-4150 3025)(-2900 3025);
WIRE 16 2175 (-2900 3125)(-2900 3025);
WIRE 16 2175 (-4150 3125)(-4150 3025);
WIRE 16 2175 (-4150 3125)(-2900 3125);
WIRE 16 -1 (-10100 3175)(-9125 3175);
FORCEPROP 2 LAST SIG_NAME FM_PVCCFA_EHV_CPU0_EN
J 0
(-10035 3185);
DISPLAY 0.617021 (-10035 3185);
WIRE 17 273 (-11500 1725)(-9929 1725);
WIRE 17 273 (-9929 1725)(-9929 1525);
WIRE 17 273 (-11500 1725)(-11500 1525);
WIRE 17 273 (-11500 1525)(-9929 1525);
WIRE 17 273 (-11300 5125)(-11025 5125);
WIRE 17 273 (-11025 5675)(-11025 5125);
WIRE 17 273 (-11300 5125)(-11300 5675);
WIRE 17 273 (-11300 5675)(-11025 5675);
WIRE 17 273 (-11300 4025)(-11025 4025);
WIRE 17 273 (-11025 4575)(-11025 4025);
WIRE 17 273 (-11300 4025)(-11300 4575);
WIRE 17 273 (-11300 4575)(-11025 4575);
WIRE 16 -1 (-11050 4475)(-10125 4475);
FORCEPROP 2 LAST SIG_NAME VSENSE_PVCCFA_EHV_CPU0_DP
J 0
(-10960 4485);
DISPLAY 0.617021 (-10960 4485);
WIRE 16 -1 (-10025 4475)(-10125 4475);
WIRE 16 -1 (-10125 4475)(-10125 4625);
WIRE 16 -1 (-10125 4625)(-9925 4625);
WIRE 16 -1 (-10500 6425)(-9300 6425);
FORCEPROP 2 LAST SIG_NAME SMB_VR_3V3AUX_SCL_R2
J 0
(-10435 6435);
DISPLAY 0.617021 (-10435 6435);
WIRE 16 -1 (-9300 6275)(-10500 6275);
FORCEPROP 2 LAST SIG_NAME SMB_VR_3V3AUX_SDA_R2
J 0
(-10435 6285);
DISPLAY 0.617021 (-10435 6285);
WIRE 16 -1 (-10450 7125)(-9625 7125);
FORCEPROP 2 LAST SIG_NAME SVID_CLK0_CPU0_R
J 0
(-10360 7135);
DISPLAY 0.617021 (-10360 7135);
WIRE 16 -1 (-9625 7125)(-9300 7125);
WIRE 16 -1 (-9625 7325)(-9625 7125);
WIRE 16 -1 (-10275 7325)(-9625 7325);
WIRE 16 -1 (-10450 7425)(-9300 7425);
FORCEPROP 2 LAST SIG_NAME FM_PVCCINFAON_CPU0_EN
J 0
(-10360 7435);
DISPLAY 0.617021 (-10360 7435);
WIRE 16 -1 (-10450 6975)(-9700 6975);
FORCEPROP 2 LAST SIG_NAME SVID_DIO0_CPU0_R
J 0
(-10360 6985);
DISPLAY 0.617021 (-10360 6985);
WIRE 16 -1 (-9700 6975)(-9300 6975);
WIRE 16 -1 (-9700 7225)(-10275 7225);
WIRE 16 -1 (-9700 7225)(-9700 6975);
WIRE 16 -1 (-10450 7575)(-9300 7575);
FORCEPROP 2 LAST SIG_NAME PWRGD_PVCCINFAON_CPU0
J 0
(-10360 7585);
DISPLAY 0.617021 (-10360 7585);
WIRE 16 -1 (-10450 6825)(-9300 6825);
FORCEPROP 2 LAST SIG_NAME SVID_ALERT0_CPU0_R_N
J 0
(-10360 6835);
DISPLAY 0.617021 (-10360 6835);
WIRE 16 -1 (-9775 4475)(-8950 4475);
FORCEPROP 2 LAST SIG_NAME SH_PVCCFA_EHV_CPU0
J 0
(-9685 4485);
DISPLAY 0.617021 (-9685 4485);
WIRE 16 -1 (-9775 5575)(-8950 5575);
FORCEPROP 2 LAST SIG_NAME SH_PVCCINFAON_CPU0
J 0
(-9610 5585);
DISPLAY 0.617021 (-9610 5585);
WIRE 16 -1 (-10825 2475)(-9975 2475);
FORCEPROP 2 LAST SIG_NAME PVCCINFAON_CPU0_VREF
J 0
(-10785 2485);
DISPLAY 0.617021 (-10785 2485);
WIRE 16 -1 (-9125 2775)(-10100 2775);
FORCEPROP 2 LAST SIG_NAME PWRGD_PVCCFA_EHV_CPU0
J 0
(-10035 2785);
DISPLAY 0.617021 (-10035 2785);
WIRE 16 -1 (-10125 5725)(-9925 5725);
WIRE 16 -1 (-10025 5575)(-10125 5575);
WIRE 16 -1 (-10125 5575)(-10125 5725);
WIRE 16 -1 (-11050 5575)(-10125 5575);
FORCEPROP 2 LAST SIG_NAME VSENSE_PVCCINFAON_CPU0_DP
J 0
(-10960 5585);
DISPLAY 0.617021 (-10960 5585);
DOT 1 (-5575 7175);
DOT 1 (-5925 7575);
DOT 1 (-8825 2225);
DOT 1 (-3750 2675);
DOT 1 (-5175 7575);
DOT 1 (-5175 7175);
DOT 1 (-5175 7100);
DOT 1 (-5575 7575);
DOT 1 (-5575 7100);
DOT 1 (-5175 6700);
DOT 1 (-4100 3075);
DOT 1 (-5250 2375);
DOT 1 (-6000 2675);
DOT 1 (-6000 2375);
DOT 1 (-7750 2125);
DOT 1 (-7750 1725);
DOT 1 (-8675 7725);
DOT 1 (-8675 7575);
DOT 1 (-8675 7425);
DOT 1 (-9625 7125);
DOT 1 (-9700 6975);
DOT 1 (-8400 5575);
DOT 1 (-8400 5200);
DOT 1 (-8400 4475);
DOT 1 (-8400 4100);
DOT 1 (-10650 7325);
DOT 1 (-10125 5575);
DOT 1 (-10125 5200);
DOT 1 (-10125 4475);
DOT 1 (-10125 4100);
DOT 1 (-8550 3175);
DOT 1 (-8550 2925);
DOT 1 (-8075 2125);
DOT 1 (-8500 2225);
DOT 1 (-8550 2775);
DOT 1 (-9350 3575);
DOT 1 (-9550 2225);
DOT 1 (-9750 2475);
DOT 1 (-8500 1725);
FORCENOTE
LOAD-LINE=2.2 MOHM
(-4080 6973) 0;
DISPLAY LEFT (-4080 6973);
DISPLAY 0.936170 (-4080 6973);
PAINT RED (-4080 6973);
FORCENOTE
SLEW RATE=18A/US(EMR 20.2A/US)
(-4075 7055) 0;
DISPLAY LEFT (-4075 7055);
DISPLAY 0.936170 (-4075 7055);
PAINT RED (-4075 7055);
FORCENOTE
CURRENT STEP=15A(38A-53A)(EMR 31A-46A)
(-4075 7130) 0;
DISPLAY LEFT (-4075 7130);
DISPLAY 0.936170 (-4075 7130);
PAINT RED (-4075 7130);
FORCENOTE
OCP=69A(130%)
(-4075 7205) 0;
DISPLAY LEFT (-4075 7205);
DISPLAY 0.936170 (-4075 7205);
PAINT RED (-4075 7205);
FORCENOTE
MAX CURRENT=53A(EMR 46A)
(-4076 7283) 0;
DISPLAY LEFT (-4076 7283);
DISPLAY 0.936170 (-4076 7283);
PAINT RED (-4076 7283);
FORCENOTE
TDC=48A(EMR 42A)
(-4075 7355) 0;
DISPLAY LEFT (-4075 7355);
DISPLAY 0.936170 (-4075 7355);
PAINT RED (-4075 7355);
FORCENOTE
(EMR 1.05VAMX/0.93VMIN)
(-4075 7430) 0;
DISPLAY LEFT (-4075 7430);
DISPLAY 0.936170 (-4075 7430);
PAINT RED (-4075 7430);
FORCENOTE
TOTAL TOLERANCE=1.05VMAX/0.909VMIN
(-4075 7496) 0;
DISPLAY LEFT (-4075 7496);
DISPLAY 0.936170 (-4075 7496);
PAINT RED (-4075 7496);
FORCENOTE
DC=+/-0.5%@1V
(-4075 7575) 0;
DISPLAY LEFT (-4075 7575);
DISPLAY 0.936170 (-4075 7575);
PAINT WHITE (-4075 7575);
FORCENOTE
RIPPLE=+/-8MV
(-4075 7647) 0;
DISPLAY LEFT (-4075 7647);
DISPLAY 0.936170 (-4075 7647);
PAINT RED (-4075 7647);
FORCENOTE
VID=0.7V~1.05V(TYP=1.0V)
(-4075 7722) 0;
DISPLAY LEFT (-4075 7722);
DISPLAY 0.936170 (-4075 7722);
PAINT WHITE (-4075 7722);
FORCENOTE
VBOOT=1.0V
(-4075 7797) 0;
DISPLAY LEFT (-4075 7797);
DISPLAY 0.936170 (-4075 7797);
PAINT WHITE (-4075 7797);
FORCENOTE
PVCCINFAON_CPU0 SPECIFICATION
(-4075 7900) 0;
DISPLAY LEFT (-4075 7900);
DISPLAY 1.021277 (-4075 7900);
PAINT WHITE (-4075 7900);
FORCENOTE
WORK FREQUENCY=700KHZ
(-4075 6905) 0;
DISPLAY LEFT (-4075 6905);
DISPLAY 0.936170 (-4075 6905);
PAINT WHITE (-4075 6905);
FORCENOTE
SETVID RATE=2.5MV/US (FAST)
(-4075 6655) 0;
DISPLAY LEFT (-4075 6655);
DISPLAY 0.936170 (-4075 6655);
PAINT WHITE (-4075 6655);
FORCENOTE
VBOOT=1.8V
(-4071 6292) 0;
DISPLAY LEFT (-4071 6292);
DISPLAY 0.936170 (-4071 6292);
PAINT WHITE (-4071 6292);
FORCENOTE
DIFFERENTIAL PAIR
(-11300 3900) 0;
DISPLAY LEFT (-11300 3900);
DISPLAY 1.021277 (-11300 3900);
PAINT WHITE (-11300 3900);
FORCENOTE
DIFFERENTIAL PAIR
(-11300 5000) 0;
DISPLAY LEFT (-11300 5000);
DISPLAY 1.021277 (-11300 5000);
PAINT WHITE (-11300 5000);
FORCENOTE
TRACE WIDTH = 10MIL
(-11300 4925) 0;
DISPLAY LEFT (-11300 4925);
DISPLAY 1.021277 (-11300 4925);
PAINT WHITE (-11300 4925);
FORCENOTE
TRACE SPACING = 5MIL
(-11300 4850) 0;
DISPLAY LEFT (-11300 4850);
DISPLAY 1.021277 (-11300 4850);
PAINT WHITE (-11300 4850);
FORCENOTE
TRACE WIDTH = 10MIL
(-11300 3825) 0;
DISPLAY LEFT (-11300 3825);
DISPLAY 1.021277 (-11300 3825);
PAINT WHITE (-11300 3825);
FORCENOTE
CONFIRM ADDRESS SETTING
(-9600 2550) 0;
DISPLAY LEFT (-9600 2550);
DISPLAY 1.021277 (-9600 2550);
PAINT SKYBLUE (-9600 2550);
FORCENOTE
SET FW CODE FUNCTION TO BVR_EN
(-10775 3400) 0;
DISPLAY LEFT (-10775 3400);
DISPLAY 1.021277 (-10775 3400);
PAINT SKYBLUE (-10775 3400);
FORCENOTE
TRACE SPACING = 5MIL
(-11300 3750) 0;
DISPLAY LEFT (-11300 3750);
DISPLAY 1.021277 (-11300 3750);
PAINT WHITE (-11300 3750);
FORCENOTE
SVID / I2C ADDRESS
(-11450 1750) 0;
DISPLAY LEFT (-11450 1750);
DISPLAY 1.170213 (-11450 1750);
PAINT WHITE (-11450 1750);
FORCENOTE
02H
(-10925 1550) 0;
DISPLAY LEFT (-10925 1550);
DISPLAY 0.638298 (-10925 1550);
PAINT WHITE (-10925 1550);
FORCENOTE
PVCCFA_EHV_CPU0
(-11475 1550) 0;
DISPLAY LEFT (-11475 1550);
DISPLAY 0.638298 (-11475 1550);
PAINT WHITE (-11475 1550);
FORCENOTE
61H/C2H
(-10625 1550) 0;
DISPLAY LEFT (-10625 1550);
DISPLAY 0.638298 (-10625 1550);
PAINT WHITE (-10625 1550);
FORCENOTE
PVCCINFAON_CPU0
(-11475 1625) 0;
DISPLAY LEFT (-11475 1625);
DISPLAY 0.638298 (-11475 1625);
PAINT WHITE (-11475 1625);
FORCENOTE
RAIL
(-11325 1675) 0;
DISPLAY LEFT (-11325 1675);
DISPLAY 0.808511 (-11325 1675);
PAINT WHITE (-11325 1675);
FORCENOTE
SVID
(-10950 1675) 0;
DISPLAY LEFT (-10950 1675);
DISPLAY 0.808511 (-10950 1675);
PAINT WHITE (-10950 1675);
FORCENOTE
01H
(-10925 1625) 0;
DISPLAY LEFT (-10925 1625);
DISPLAY 0.638298 (-10925 1625);
PAINT WHITE (-10925 1625);
FORCENOTE
I2C(7BIT/8BIT)
(-10625 1675) 0;
DISPLAY LEFT (-10625 1675);
DISPLAY 0.808511 (-10625 1675);
PAINT WHITE (-10625 1675);
FORCENOTE
61H/C2H
(-10625 1625) 0;
DISPLAY LEFT (-10625 1625);
DISPLAY 0.638298 (-10625 1625);
PAINT WHITE (-10625 1625);
FORCENOTE
DC=+/-0.5% OF VID
(-4071 6075) 0;
DISPLAY LEFT (-4071 6075);
DISPLAY 0.936170 (-4071 6075);
PAINT WHITE (-4071 6075);
FORCENOTE
MAX CURRENT=6.25A
(-4066 5842) 0;
DISPLAY LEFT (-4066 5842);
DISPLAY 0.936170 (-4066 5842);
PAINT RED (-4066 5842);
FORCENOTE
RIPPLE=+/-9MV
(-4071 6142) 0;
DISPLAY LEFT (-4071 6142);
DISPLAY 0.936170 (-4071 6142);
PAINT RED (-4071 6142);
FORCENOTE
PROTOCOL ID=09H (VR14 5MV VID)
(-4080 6743) 0;
DISPLAY LEFT (-4080 6743);
DISPLAY 0.936170 (-4080 6743);
PAINT WHITE (-4080 6743);
FORCENOTE
SVID ADDRESS=01H BUS#0
(-4075 6830) 0;
DISPLAY LEFT (-4075 6830);
DISPLAY 0.936170 (-4075 6830);
PAINT WHITE (-4075 6830);
FORCENOTE
LOAD-LINE=N/A
(-4066 5532) 0;
DISPLAY LEFT (-4066 5532);
DISPLAY 0.936170 (-4066 5532);
PAINT WHITE (-4066 5532);
FORCENOTE
OCP=15A
(-4066 5767) 0;
DISPLAY LEFT (-4066 5767);
DISPLAY 0.936170 (-4066 5767);
PAINT WHITE (-4066 5767);
FORCENOTE
TDC=5A
(-4066 5917) 0;
DISPLAY LEFT (-4066 5917);
DISPLAY 0.936170 (-4066 5917);
PAINT RED (-4066 5917);
FORCENOTE
SLEW RATE=5.3A
(-4066 5607) 0;
DISPLAY LEFT (-4066 5607);
DISPLAY 0.936170 (-4066 5607);
PAINT RED (-4066 5607);
FORCENOTE
PVCCFA_EHV_CPU0 SPECIFICATION
(-4075 6400) 0;
DISPLAY LEFT (-4075 6400);
DISPLAY 1.021277 (-4075 6400);
PAINT WHITE (-4075 6400);
FORCENOTE
VID=1.6V~1.87V(TYP=1.8V)
(-4071 6217) 0;
DISPLAY LEFT (-4071 6217);
DISPLAY 0.936170 (-4071 6217);
PAINT WHITE (-4071 6217);
FORCENOTE
TOTAL TOLERANCE=1.841VMAX/1.749VMIN
(-4071 5991) 0;
DISPLAY LEFT (-4071 5991);
DISPLAY 0.936170 (-4071 5991);
PAINT RED (-4071 5991);
FORCENOTE
PDG REV.1.6 FOR SPR+HBM
(-4080 6573) 0;
DISPLAY LEFT (-4080 6573);
DISPLAY 0.936170 (-4080 6573);
PAINT RED (-4080 6573);
FORCENOTE
20220808 UPDATE PDG REV 1.6
(-4325 4950) 0;
DISPLAY LEFT (-4325 4950);
DISPLAY 1.595745 (-4325 4950);
FORCENOTE
PDG REV.1.6 FOR SPR+HBM
(-4071 5125) 0;
DISPLAY LEFT (-4071 5125);
DISPLAY 0.936170 (-4071 5125);
PAINT RED (-4071 5125);
FORCENOTE
SETVID RATE=10MV/US (FAST)
(-4066 5207) 0;
DISPLAY LEFT (-4066 5207);
DISPLAY 0.936170 (-4066 5207);
PAINT WHITE (-4066 5207);
FORCENOTE
PROTOCOL ID=04H (VR13 10MV VID)
(-4071 5295) 0;
DISPLAY LEFT (-4071 5295);
DISPLAY 0.936170 (-4071 5295);
PAINT WHITE (-4071 5295);
FORCENOTE
SVID ADDRESS=02H BUS#0
(-4066 5382) 0;
DISPLAY LEFT (-4066 5382);
DISPLAY 0.936170 (-4066 5382);
PAINT WHITE (-4066 5382);
FORCENOTE
WORK FREQUENCY=600KHZ
(-4066 5457) 0;
DISPLAY LEFT (-4066 5457);
DISPLAY 0.936170 (-4066 5457);
PAINT WHITE (-4066 5457);
FORCENOTE
CURRENT STEP=4.75A(1.5A-6.25A)
(-4066 5692) 0;
DISPLAY LEFT (-4066 5692);
DISPLAY 0.936170 (-4066 5692);
PAINT RED (-4066 5692);
FORCENOTE
20220725 CONNECT TO CPLD
(-3775 3150) 0;
DISPLAY LEFT (-3775 3150);
DISPLAY 0.680851 (-3775 3150);
PAINT WHITE (-3775 3150);
QUIT
